FILE_TYPE = MACRO_DRAWING;
SET COLOR_WIRE YELLOW;
SET COLOR_PROP MONO;
SET COLOR_DOT WHITE;
SET COLOR_ARC YELLOW;
SET COLOR_BODY GREEN;
SET COLOR_NOTE MONO;
SET PROP_DISPLAY VALUE;
SET PAGE_NUMBER P24;
FORCEADD OFFPAGE..5
(-6375 500);
FORCEPROP 2 LAST $XR0 45 
J 0
(-6629 500);
DISPLAY 0.638298 (-6629 500);
PAINT MONO (-6629 500);
FORCEPROP 2 LAST $XR1 46 
J 0
(-6719 500);
DISPLAY 0.638298 (-6719 500);
PAINT MONO (-6719 500);
FORCEPROP 2 LAST CDS_LIB mstr_standard
J 0
(-6375 500);
PAINT MONO (-6375 500);
DISPLAY INVISIBLE (-6375 500);
FORCEPROP 1 LAST OFFPAGE TRUE
J 0
(-6050 375);
DISPLAY 1.170213 (-6050 375);
PAINT GREEN (-6050 375);
DISPLAY INVISIBLE (-6050 375);
FORCEPROP 1 LAST COMMENT_BODY TRUE
J 0
(-6275 425);
DISPLAY 1.170213 (-6275 425);
PAINT GREEN (-6275 425);
DISPLAY INVISIBLE (-6275 425);
FORCEPROP 2 LAST PATH I1
J 0
(-6325 575);
DISPLAY 1.021277 (-6325 575);
PAINT ORANGE (-6325 575);
DISPLAY INVISIBLE (-6325 575);
FORCEADD TAP..6
(-5525 750);
FORCEPROP 3 LASTPIN (-5475 750) SIG_NAME M_B_CLK_DN<3>
J 0
(-5465 760);
DISPLAY 0.659574 (-5465 760);
PAINT MONO (-5465 760);
DISPLAY INVISIBLE (-5465 760);
FORCEPROP 1 LASTPIN (-5475 750) BN 3
J 0
(-5527 758);
DISPLAY 0.617021 (-5527 758);
PAINT PINK (-5527 758);
FORCEPROP 2 LAST CDS_LIB mstr_standard
J 0
(-5525 750);
PAINT MONO (-5525 750);
DISPLAY INVISIBLE (-5525 750);
FORCEPROP 1 LAST BODY_TYPE PLUMBING
J 0
(-5525 700);
DISPLAY 1.595745 (-5525 700);
PAINT GREEN (-5525 700);
DISPLAY INVISIBLE (-5525 700);
FORCEPROP 1 LAST HDL_TAP TRUE
J 0
(-5200 625);
DISPLAY 1.595745 (-5200 625);
PAINT GREEN (-5200 625);
DISPLAY INVISIBLE (-5200 625);
FORCEPROP 1 LAST PATH I10
J 0
(-5527 750);
DISPLAY 0.872340 (-5527 750);
PAINT GREEN (-5527 750);
DISPLAY INVISIBLE (-5527 750);
FORCEADD TAP..6
R 2
(-2800 1550);
FORCEPROP 3 LASTPIN (-2850 1550) SIG_NAME M_B_ODT<3>
J 0
(-2840 1560);
DISPLAY 0.659574 (-2840 1560);
PAINT MONO (-2840 1560);
DISPLAY INVISIBLE (-2840 1560);
FORCEPROP 1 LASTPIN (-2850 1550) BN 3
J 2
(-2798 1558);
DISPLAY 0.617021 (-2798 1558);
PAINT PINK (-2798 1558);
FORCEPROP 2 LAST CDS_LIB mstr_standard
J 0
(-2800 1550);
PAINT MONO (-2800 1550);
DISPLAY INVISIBLE (-2800 1550);
FORCEPROP 1 LAST BODY_TYPE PLUMBING
J 2
(-2800 1500);
DISPLAY 1.595745 (-2800 1500);
PAINT GREEN (-2800 1500);
DISPLAY INVISIBLE (-2800 1500);
FORCEPROP 1 LAST HDL_TAP TRUE
J 2
(-3125 1425);
DISPLAY 1.595745 (-3125 1425);
PAINT GREEN (-3125 1425);
DISPLAY INVISIBLE (-3125 1425);
FORCEPROP 1 LAST PATH I100
J 2
(-2798 1550);
DISPLAY 0.872340 (-2798 1550);
PAINT GREEN (-2798 1550);
DISPLAY INVISIBLE (-2798 1550);
FORCEADD TAP..6
R 2
(-2800 1450);
FORCEPROP 3 LASTPIN (-2850 1450) SIG_NAME M_B_ODT<1>
J 0
(-2840 1460);
DISPLAY 0.659574 (-2840 1460);
PAINT MONO (-2840 1460);
DISPLAY INVISIBLE (-2840 1460);
FORCEPROP 1 LASTPIN (-2850 1450) BN 1
J 2
(-2798 1458);
DISPLAY 0.617021 (-2798 1458);
PAINT PINK (-2798 1458);
FORCEPROP 2 LAST CDS_LIB mstr_standard
J 0
(-2800 1450);
PAINT MONO (-2800 1450);
DISPLAY INVISIBLE (-2800 1450);
FORCEPROP 1 LAST BODY_TYPE PLUMBING
J 2
(-2800 1400);
DISPLAY 1.595745 (-2800 1400);
PAINT GREEN (-2800 1400);
DISPLAY INVISIBLE (-2800 1400);
FORCEPROP 1 LAST HDL_TAP TRUE
J 2
(-3125 1325);
DISPLAY 1.595745 (-3125 1325);
PAINT GREEN (-3125 1325);
DISPLAY INVISIBLE (-3125 1325);
FORCEPROP 1 LAST PATH I101
J 2
(-2798 1450);
DISPLAY 0.872340 (-2798 1450);
PAINT GREEN (-2798 1450);
DISPLAY INVISIBLE (-2798 1450);
FORCEADD TAP..6
R 2
(-2800 1650);
FORCEPROP 3 LASTPIN (-2850 1650) SIG_NAME M_B_CKE<0>
J 0
(-2840 1660);
DISPLAY 0.659574 (-2840 1660);
PAINT MONO (-2840 1660);
DISPLAY INVISIBLE (-2840 1660);
FORCEPROP 1 LASTPIN (-2850 1650) BN 0
J 2
(-2798 1658);
DISPLAY 0.617021 (-2798 1658);
PAINT PINK (-2798 1658);
FORCEPROP 2 LAST CDS_LIB mstr_standard
J 0
(-2800 1650);
PAINT MONO (-2800 1650);
DISPLAY INVISIBLE (-2800 1650);
FORCEPROP 1 LAST BODY_TYPE PLUMBING
J 2
(-2800 1600);
DISPLAY 1.595745 (-2800 1600);
PAINT GREEN (-2800 1600);
DISPLAY INVISIBLE (-2800 1600);
FORCEPROP 1 LAST HDL_TAP TRUE
J 2
(-3125 1525);
DISPLAY 1.595745 (-3125 1525);
PAINT GREEN (-3125 1525);
DISPLAY INVISIBLE (-3125 1525);
FORCEPROP 1 LAST PATH I102
J 2
(-2798 1650);
DISPLAY 0.872340 (-2798 1650);
PAINT GREEN (-2798 1650);
DISPLAY INVISIBLE (-2798 1650);
FORCEADD TAP..6
R 2
(-2800 1500);
FORCEPROP 3 LASTPIN (-2850 1500) SIG_NAME M_B_ODT<2>
J 0
(-2840 1510);
DISPLAY 0.659574 (-2840 1510);
PAINT MONO (-2840 1510);
DISPLAY INVISIBLE (-2840 1510);
FORCEPROP 1 LASTPIN (-2850 1500) BN 2
J 2
(-2798 1508);
DISPLAY 0.617021 (-2798 1508);
PAINT PINK (-2798 1508);
FORCEPROP 2 LAST CDS_LIB mstr_standard
J 0
(-2800 1500);
PAINT MONO (-2800 1500);
DISPLAY INVISIBLE (-2800 1500);
FORCEPROP 1 LAST BODY_TYPE PLUMBING
J 2
(-2800 1450);
DISPLAY 1.595745 (-2800 1450);
PAINT GREEN (-2800 1450);
DISPLAY INVISIBLE (-2800 1450);
FORCEPROP 1 LAST HDL_TAP TRUE
J 2
(-3125 1375);
DISPLAY 1.595745 (-3125 1375);
PAINT GREEN (-3125 1375);
DISPLAY INVISIBLE (-3125 1375);
FORCEPROP 1 LAST PATH I103
J 2
(-2798 1500);
DISPLAY 0.872340 (-2798 1500);
PAINT GREEN (-2798 1500);
DISPLAY INVISIBLE (-2798 1500);
FORCEADD TAP..6
R 2
(-2800 1750);
FORCEPROP 3 LASTPIN (-2850 1750) SIG_NAME M_B_CKE<2>
J 0
(-2840 1760);
DISPLAY 0.659574 (-2840 1760);
PAINT MONO (-2840 1760);
DISPLAY INVISIBLE (-2840 1760);
FORCEPROP 1 LASTPIN (-2850 1750) BN 2
J 2
(-2798 1758);
DISPLAY 0.617021 (-2798 1758);
PAINT PINK (-2798 1758);
FORCEPROP 2 LAST CDS_LIB mstr_standard
J 0
(-2800 1750);
PAINT MONO (-2800 1750);
DISPLAY INVISIBLE (-2800 1750);
FORCEPROP 1 LAST BODY_TYPE PLUMBING
J 2
(-2800 1700);
DISPLAY 1.595745 (-2800 1700);
PAINT GREEN (-2800 1700);
DISPLAY INVISIBLE (-2800 1700);
FORCEPROP 1 LAST HDL_TAP TRUE
J 2
(-3125 1625);
DISPLAY 1.595745 (-3125 1625);
PAINT GREEN (-3125 1625);
DISPLAY INVISIBLE (-3125 1625);
FORCEPROP 1 LAST PATH I104
J 2
(-2798 1750);
DISPLAY 0.872340 (-2798 1750);
PAINT GREEN (-2798 1750);
DISPLAY INVISIBLE (-2798 1750);
FORCEADD TAP..6
R 2
(-2800 1700);
FORCEPROP 3 LASTPIN (-2850 1700) SIG_NAME M_B_CKE<1>
J 0
(-2840 1710);
DISPLAY 0.659574 (-2840 1710);
PAINT MONO (-2840 1710);
DISPLAY INVISIBLE (-2840 1710);
FORCEPROP 1 LASTPIN (-2850 1700) BN 1
J 2
(-2798 1708);
DISPLAY 0.617021 (-2798 1708);
PAINT PINK (-2798 1708);
FORCEPROP 2 LAST CDS_LIB mstr_standard
J 0
(-2800 1700);
PAINT MONO (-2800 1700);
DISPLAY INVISIBLE (-2800 1700);
FORCEPROP 1 LAST BODY_TYPE PLUMBING
J 2
(-2800 1650);
DISPLAY 1.595745 (-2800 1650);
PAINT GREEN (-2800 1650);
DISPLAY INVISIBLE (-2800 1650);
FORCEPROP 1 LAST HDL_TAP TRUE
J 2
(-3125 1575);
DISPLAY 1.595745 (-3125 1575);
PAINT GREEN (-3125 1575);
DISPLAY INVISIBLE (-3125 1575);
FORCEPROP 1 LAST PATH I105
J 2
(-2798 1700);
DISPLAY 0.872340 (-2798 1700);
PAINT GREEN (-2798 1700);
DISPLAY INVISIBLE (-2798 1700);
FORCEADD TAP..6
R 2
(-2800 1900);
FORCEPROP 3 LASTPIN (-2850 1900) SIG_NAME M_B_MA<0>
J 0
(-2840 1910);
DISPLAY 0.659574 (-2840 1910);
PAINT MONO (-2840 1910);
DISPLAY INVISIBLE (-2840 1910);
FORCEPROP 1 LASTPIN (-2850 1900) BN 0
J 2
(-2798 1908);
DISPLAY 0.617021 (-2798 1908);
PAINT PINK (-2798 1908);
FORCEPROP 2 LAST CDS_LIB mstr_standard
J 0
(-2800 1900);
PAINT MONO (-2800 1900);
DISPLAY INVISIBLE (-2800 1900);
FORCEPROP 1 LAST BODY_TYPE PLUMBING
J 2
(-2800 1850);
DISPLAY 1.595745 (-2800 1850);
PAINT GREEN (-2800 1850);
DISPLAY INVISIBLE (-2800 1850);
FORCEPROP 1 LAST HDL_TAP TRUE
J 2
(-3125 1775);
DISPLAY 1.595745 (-3125 1775);
PAINT GREEN (-3125 1775);
DISPLAY INVISIBLE (-3125 1775);
FORCEPROP 1 LAST PATH I106
J 2
(-2798 1900);
DISPLAY 0.872340 (-2798 1900);
PAINT GREEN (-2798 1900);
DISPLAY INVISIBLE (-2798 1900);
FORCEADD TAP..6
R 2
(-2800 1800);
FORCEPROP 3 LASTPIN (-2850 1800) SIG_NAME M_B_CKE<3>
J 0
(-2840 1810);
DISPLAY 0.659574 (-2840 1810);
PAINT MONO (-2840 1810);
DISPLAY INVISIBLE (-2840 1810);
FORCEPROP 1 LASTPIN (-2850 1800) BN 3
J 2
(-2798 1808);
DISPLAY 0.617021 (-2798 1808);
PAINT PINK (-2798 1808);
FORCEPROP 2 LAST CDS_LIB mstr_standard
J 0
(-2800 1800);
PAINT MONO (-2800 1800);
DISPLAY INVISIBLE (-2800 1800);
FORCEPROP 1 LAST BODY_TYPE PLUMBING
J 2
(-2800 1750);
DISPLAY 1.595745 (-2800 1750);
PAINT GREEN (-2800 1750);
DISPLAY INVISIBLE (-2800 1750);
FORCEPROP 1 LAST HDL_TAP TRUE
J 2
(-3125 1675);
DISPLAY 1.595745 (-3125 1675);
PAINT GREEN (-3125 1675);
DISPLAY INVISIBLE (-3125 1675);
FORCEPROP 1 LAST PATH I107
J 2
(-2798 1800);
DISPLAY 0.872340 (-2798 1800);
PAINT GREEN (-2798 1800);
DISPLAY INVISIBLE (-2798 1800);
FORCEADD TAP..6
R 2
(-2800 2100);
FORCEPROP 3 LASTPIN (-2850 2100) SIG_NAME M_B_MA<4>
J 0
(-2840 2110);
DISPLAY 0.659574 (-2840 2110);
PAINT MONO (-2840 2110);
DISPLAY INVISIBLE (-2840 2110);
FORCEPROP 1 LASTPIN (-2850 2100) BN 4
J 2
(-2798 2108);
DISPLAY 0.617021 (-2798 2108);
PAINT PINK (-2798 2108);
FORCEPROP 2 LAST CDS_LIB mstr_standard
J 0
(-2800 2100);
PAINT MONO (-2800 2100);
DISPLAY INVISIBLE (-2800 2100);
FORCEPROP 1 LAST BODY_TYPE PLUMBING
J 2
(-2800 2050);
DISPLAY 1.595745 (-2800 2050);
PAINT GREEN (-2800 2050);
DISPLAY INVISIBLE (-2800 2050);
FORCEPROP 1 LAST HDL_TAP TRUE
J 2
(-3125 1975);
DISPLAY 1.595745 (-3125 1975);
PAINT GREEN (-3125 1975);
DISPLAY INVISIBLE (-3125 1975);
FORCEPROP 1 LAST PATH I108
J 2
(-2798 2100);
DISPLAY 0.872340 (-2798 2100);
PAINT GREEN (-2798 2100);
DISPLAY INVISIBLE (-2798 2100);
FORCEADD TAP..6
R 2
(-2800 2150);
FORCEPROP 3 LASTPIN (-2850 2150) SIG_NAME M_B_MA<5>
J 0
(-2840 2160);
DISPLAY 0.659574 (-2840 2160);
PAINT MONO (-2840 2160);
DISPLAY INVISIBLE (-2840 2160);
FORCEPROP 1 LASTPIN (-2850 2150) BN 5
J 2
(-2798 2158);
DISPLAY 0.617021 (-2798 2158);
PAINT PINK (-2798 2158);
FORCEPROP 2 LAST CDS_LIB mstr_standard
J 0
(-2800 2150);
PAINT MONO (-2800 2150);
DISPLAY INVISIBLE (-2800 2150);
FORCEPROP 1 LAST BODY_TYPE PLUMBING
J 2
(-2800 2100);
DISPLAY 1.595745 (-2800 2100);
PAINT GREEN (-2800 2100);
DISPLAY INVISIBLE (-2800 2100);
FORCEPROP 1 LAST HDL_TAP TRUE
J 2
(-3125 2025);
DISPLAY 1.595745 (-3125 2025);
PAINT GREEN (-3125 2025);
DISPLAY INVISIBLE (-3125 2025);
FORCEPROP 1 LAST PATH I109
J 2
(-2798 2150);
DISPLAY 0.872340 (-2798 2150);
PAINT GREEN (-2798 2150);
DISPLAY INVISIBLE (-2798 2150);
FORCEADD TAP..6
(-5525 900);
FORCEPROP 3 LASTPIN (-5475 900) SIG_NAME M_B_CLK_DP<2>
J 0
(-5465 910);
DISPLAY 0.659574 (-5465 910);
PAINT MONO (-5465 910);
DISPLAY INVISIBLE (-5465 910);
FORCEPROP 1 LASTPIN (-5475 900) BN 2
J 0
(-5527 908);
DISPLAY 0.617021 (-5527 908);
PAINT PINK (-5527 908);
FORCEPROP 2 LAST CDS_LIB mstr_standard
J 0
(-5525 900);
PAINT MONO (-5525 900);
DISPLAY INVISIBLE (-5525 900);
FORCEPROP 1 LAST BODY_TYPE PLUMBING
J 0
(-5525 850);
DISPLAY 1.595745 (-5525 850);
PAINT GREEN (-5525 850);
DISPLAY INVISIBLE (-5525 850);
FORCEPROP 1 LAST HDL_TAP TRUE
J 0
(-5200 775);
DISPLAY 1.595745 (-5200 775);
PAINT GREEN (-5200 775);
DISPLAY INVISIBLE (-5200 775);
FORCEPROP 1 LAST PATH I11
J 0
(-5527 900);
DISPLAY 0.872340 (-5527 900);
PAINT GREEN (-5527 900);
DISPLAY INVISIBLE (-5527 900);
FORCEADD TAP..6
R 2
(-2800 2000);
FORCEPROP 3 LASTPIN (-2850 2000) SIG_NAME M_B_MA<2>
J 0
(-2840 2010);
DISPLAY 0.659574 (-2840 2010);
PAINT MONO (-2840 2010);
DISPLAY INVISIBLE (-2840 2010);
FORCEPROP 1 LASTPIN (-2850 2000) BN 2
J 2
(-2798 2008);
DISPLAY 0.617021 (-2798 2008);
PAINT PINK (-2798 2008);
FORCEPROP 2 LAST CDS_LIB mstr_standard
J 0
(-2800 2000);
PAINT MONO (-2800 2000);
DISPLAY INVISIBLE (-2800 2000);
FORCEPROP 1 LAST BODY_TYPE PLUMBING
J 2
(-2800 1950);
DISPLAY 1.595745 (-2800 1950);
PAINT GREEN (-2800 1950);
DISPLAY INVISIBLE (-2800 1950);
FORCEPROP 1 LAST HDL_TAP TRUE
J 2
(-3125 1875);
DISPLAY 1.595745 (-3125 1875);
PAINT GREEN (-3125 1875);
DISPLAY INVISIBLE (-3125 1875);
FORCEPROP 1 LAST PATH I110
J 2
(-2798 2000);
DISPLAY 0.872340 (-2798 2000);
PAINT GREEN (-2798 2000);
DISPLAY INVISIBLE (-2798 2000);
FORCEADD TAP..6
R 2
(-2800 2050);
FORCEPROP 3 LASTPIN (-2850 2050) SIG_NAME M_B_MA<3>
J 0
(-2840 2060);
DISPLAY 0.659574 (-2840 2060);
PAINT MONO (-2840 2060);
DISPLAY INVISIBLE (-2840 2060);
FORCEPROP 1 LASTPIN (-2850 2050) BN 3
J 2
(-2798 2058);
DISPLAY 0.617021 (-2798 2058);
PAINT PINK (-2798 2058);
FORCEPROP 2 LAST CDS_LIB mstr_standard
J 0
(-2800 2050);
PAINT MONO (-2800 2050);
DISPLAY INVISIBLE (-2800 2050);
FORCEPROP 1 LAST BODY_TYPE PLUMBING
J 2
(-2800 2000);
DISPLAY 1.595745 (-2800 2000);
PAINT GREEN (-2800 2000);
DISPLAY INVISIBLE (-2800 2000);
FORCEPROP 1 LAST HDL_TAP TRUE
J 2
(-3125 1925);
DISPLAY 1.595745 (-3125 1925);
PAINT GREEN (-3125 1925);
DISPLAY INVISIBLE (-3125 1925);
FORCEPROP 1 LAST PATH I111
J 2
(-2798 2050);
DISPLAY 0.872340 (-2798 2050);
PAINT GREEN (-2798 2050);
DISPLAY INVISIBLE (-2798 2050);
FORCEADD TAP..6
R 2
(-2800 1950);
FORCEPROP 3 LASTPIN (-2850 1950) SIG_NAME M_B_MA<1>
J 0
(-2840 1960);
DISPLAY 0.659574 (-2840 1960);
PAINT MONO (-2840 1960);
DISPLAY INVISIBLE (-2840 1960);
FORCEPROP 1 LASTPIN (-2850 1950) BN 1
J 2
(-2798 1958);
DISPLAY 0.617021 (-2798 1958);
PAINT PINK (-2798 1958);
FORCEPROP 2 LAST CDS_LIB mstr_standard
J 0
(-2800 1950);
PAINT MONO (-2800 1950);
DISPLAY INVISIBLE (-2800 1950);
FORCEPROP 1 LAST BODY_TYPE PLUMBING
J 2
(-2800 1900);
DISPLAY 1.595745 (-2800 1900);
PAINT GREEN (-2800 1900);
DISPLAY INVISIBLE (-2800 1900);
FORCEPROP 1 LAST HDL_TAP TRUE
J 2
(-3125 1825);
DISPLAY 1.595745 (-3125 1825);
PAINT GREEN (-3125 1825);
DISPLAY INVISIBLE (-3125 1825);
FORCEPROP 1 LAST PATH I112
J 2
(-2798 1950);
DISPLAY 0.872340 (-2798 1950);
PAINT GREEN (-2798 1950);
DISPLAY INVISIBLE (-2798 1950);
FORCEADD TAP..6
R 2
(-2800 2400);
FORCEPROP 3 LASTPIN (-2850 2400) SIG_NAME M_B_MA<10>
J 0
(-2840 2410);
DISPLAY 0.659574 (-2840 2410);
PAINT MONO (-2840 2410);
DISPLAY INVISIBLE (-2840 2410);
FORCEPROP 1 LASTPIN (-2850 2400) BN 10
J 2
(-2798 2408);
DISPLAY 0.617021 (-2798 2408);
PAINT PINK (-2798 2408);
FORCEPROP 2 LAST CDS_LIB mstr_standard
J 0
(-2800 2400);
PAINT MONO (-2800 2400);
DISPLAY INVISIBLE (-2800 2400);
FORCEPROP 1 LAST BODY_TYPE PLUMBING
J 2
(-2800 2350);
DISPLAY 1.595745 (-2800 2350);
PAINT GREEN (-2800 2350);
DISPLAY INVISIBLE (-2800 2350);
FORCEPROP 1 LAST HDL_TAP TRUE
J 2
(-3125 2275);
DISPLAY 1.595745 (-3125 2275);
PAINT GREEN (-3125 2275);
DISPLAY INVISIBLE (-3125 2275);
FORCEPROP 1 LAST PATH I113
J 2
(-2798 2400);
DISPLAY 0.872340 (-2798 2400);
PAINT GREEN (-2798 2400);
DISPLAY INVISIBLE (-2798 2400);
FORCEADD TAP..6
R 2
(-2800 2350);
FORCEPROP 3 LASTPIN (-2850 2350) SIG_NAME M_B_MA<9>
J 0
(-2840 2360);
DISPLAY 0.659574 (-2840 2360);
PAINT MONO (-2840 2360);
DISPLAY INVISIBLE (-2840 2360);
FORCEPROP 1 LASTPIN (-2850 2350) BN 9
J 2
(-2798 2358);
DISPLAY 0.617021 (-2798 2358);
PAINT PINK (-2798 2358);
FORCEPROP 2 LAST CDS_LIB mstr_standard
J 0
(-2800 2350);
PAINT MONO (-2800 2350);
DISPLAY INVISIBLE (-2800 2350);
FORCEPROP 1 LAST BODY_TYPE PLUMBING
J 2
(-2800 2300);
DISPLAY 1.595745 (-2800 2300);
PAINT GREEN (-2800 2300);
DISPLAY INVISIBLE (-2800 2300);
FORCEPROP 1 LAST HDL_TAP TRUE
J 2
(-3125 2225);
DISPLAY 1.595745 (-3125 2225);
PAINT GREEN (-3125 2225);
DISPLAY INVISIBLE (-3125 2225);
FORCEPROP 1 LAST PATH I114
J 2
(-2798 2350);
DISPLAY 0.872340 (-2798 2350);
PAINT GREEN (-2798 2350);
DISPLAY INVISIBLE (-2798 2350);
FORCEADD TAP..6
R 2
(-2800 2300);
FORCEPROP 3 LASTPIN (-2850 2300) SIG_NAME M_B_MA<8>
J 0
(-2840 2310);
DISPLAY 0.659574 (-2840 2310);
PAINT MONO (-2840 2310);
DISPLAY INVISIBLE (-2840 2310);
FORCEPROP 1 LASTPIN (-2850 2300) BN 8
J 2
(-2798 2308);
DISPLAY 0.617021 (-2798 2308);
PAINT PINK (-2798 2308);
FORCEPROP 2 LAST CDS_LIB mstr_standard
J 0
(-2800 2300);
PAINT MONO (-2800 2300);
DISPLAY INVISIBLE (-2800 2300);
FORCEPROP 1 LAST BODY_TYPE PLUMBING
J 2
(-2800 2250);
DISPLAY 1.595745 (-2800 2250);
PAINT GREEN (-2800 2250);
DISPLAY INVISIBLE (-2800 2250);
FORCEPROP 1 LAST HDL_TAP TRUE
J 2
(-3125 2175);
DISPLAY 1.595745 (-3125 2175);
PAINT GREEN (-3125 2175);
DISPLAY INVISIBLE (-3125 2175);
FORCEPROP 1 LAST PATH I115
J 2
(-2798 2300);
DISPLAY 0.872340 (-2798 2300);
PAINT GREEN (-2798 2300);
DISPLAY INVISIBLE (-2798 2300);
FORCEADD TAP..6
R 2
(-2800 2250);
FORCEPROP 3 LASTPIN (-2850 2250) SIG_NAME M_B_MA<7>
J 0
(-2840 2260);
DISPLAY 0.659574 (-2840 2260);
PAINT MONO (-2840 2260);
DISPLAY INVISIBLE (-2840 2260);
FORCEPROP 1 LASTPIN (-2850 2250) BN 7
J 2
(-2798 2258);
DISPLAY 0.617021 (-2798 2258);
PAINT PINK (-2798 2258);
FORCEPROP 2 LAST CDS_LIB mstr_standard
J 0
(-2800 2250);
PAINT MONO (-2800 2250);
DISPLAY INVISIBLE (-2800 2250);
FORCEPROP 1 LAST BODY_TYPE PLUMBING
J 2
(-2800 2200);
DISPLAY 1.595745 (-2800 2200);
PAINT GREEN (-2800 2200);
DISPLAY INVISIBLE (-2800 2200);
FORCEPROP 1 LAST HDL_TAP TRUE
J 2
(-3125 2125);
DISPLAY 1.595745 (-3125 2125);
PAINT GREEN (-3125 2125);
DISPLAY INVISIBLE (-3125 2125);
FORCEPROP 1 LAST PATH I116
J 2
(-2798 2250);
DISPLAY 0.872340 (-2798 2250);
PAINT GREEN (-2798 2250);
DISPLAY INVISIBLE (-2798 2250);
FORCEADD TAP..6
R 2
(-2800 2200);
FORCEPROP 3 LASTPIN (-2850 2200) SIG_NAME M_B_MA<6>
J 0
(-2840 2210);
DISPLAY 0.659574 (-2840 2210);
PAINT MONO (-2840 2210);
DISPLAY INVISIBLE (-2840 2210);
FORCEPROP 1 LASTPIN (-2850 2200) BN 6
J 2
(-2798 2208);
DISPLAY 0.617021 (-2798 2208);
PAINT PINK (-2798 2208);
FORCEPROP 2 LAST CDS_LIB mstr_standard
J 0
(-2800 2200);
PAINT MONO (-2800 2200);
DISPLAY INVISIBLE (-2800 2200);
FORCEPROP 1 LAST BODY_TYPE PLUMBING
J 2
(-2800 2150);
DISPLAY 1.595745 (-2800 2150);
PAINT GREEN (-2800 2150);
DISPLAY INVISIBLE (-2800 2150);
FORCEPROP 1 LAST HDL_TAP TRUE
J 2
(-3125 2075);
DISPLAY 1.595745 (-3125 2075);
PAINT GREEN (-3125 2075);
DISPLAY INVISIBLE (-3125 2075);
FORCEPROP 1 LAST PATH I117
J 2
(-2798 2200);
DISPLAY 0.872340 (-2798 2200);
PAINT GREEN (-2798 2200);
DISPLAY INVISIBLE (-2798 2200);
FORCEADD TAP..6
R 2
(-2800 2650);
FORCEPROP 3 LASTPIN (-2850 2650) SIG_NAME M_B_MA<15>
J 0
(-2840 2660);
DISPLAY 0.659574 (-2840 2660);
PAINT MONO (-2840 2660);
DISPLAY INVISIBLE (-2840 2660);
FORCEPROP 1 LASTPIN (-2850 2650) BN 15
J 2
(-2798 2658);
DISPLAY 0.617021 (-2798 2658);
PAINT PINK (-2798 2658);
FORCEPROP 2 LAST CDS_LIB mstr_standard
J 0
(-2800 2650);
PAINT MONO (-2800 2650);
DISPLAY INVISIBLE (-2800 2650);
FORCEPROP 1 LAST BODY_TYPE PLUMBING
J 2
(-2800 2600);
DISPLAY 1.595745 (-2800 2600);
PAINT GREEN (-2800 2600);
DISPLAY INVISIBLE (-2800 2600);
FORCEPROP 1 LAST HDL_TAP TRUE
J 2
(-3125 2525);
DISPLAY 1.595745 (-3125 2525);
PAINT GREEN (-3125 2525);
DISPLAY INVISIBLE (-3125 2525);
FORCEPROP 1 LAST PATH I118
J 2
(-2798 2650);
DISPLAY 0.872340 (-2798 2650);
PAINT GREEN (-2798 2650);
DISPLAY INVISIBLE (-2798 2650);
FORCEADD TAP..6
R 2
(-2800 2600);
FORCEPROP 3 LASTPIN (-2850 2600) SIG_NAME M_B_MA<14>
J 0
(-2840 2610);
DISPLAY 0.659574 (-2840 2610);
PAINT MONO (-2840 2610);
DISPLAY INVISIBLE (-2840 2610);
FORCEPROP 1 LASTPIN (-2850 2600) BN 14
J 2
(-2798 2608);
DISPLAY 0.617021 (-2798 2608);
PAINT PINK (-2798 2608);
FORCEPROP 2 LAST CDS_LIB mstr_standard
J 0
(-2800 2600);
PAINT MONO (-2800 2600);
DISPLAY INVISIBLE (-2800 2600);
FORCEPROP 1 LAST BODY_TYPE PLUMBING
J 2
(-2800 2550);
DISPLAY 1.595745 (-2800 2550);
PAINT GREEN (-2800 2550);
DISPLAY INVISIBLE (-2800 2550);
FORCEPROP 1 LAST HDL_TAP TRUE
J 2
(-3125 2475);
DISPLAY 1.595745 (-3125 2475);
PAINT GREEN (-3125 2475);
DISPLAY INVISIBLE (-3125 2475);
FORCEPROP 1 LAST PATH I119
J 2
(-2798 2600);
DISPLAY 0.872340 (-2798 2600);
PAINT GREEN (-2798 2600);
DISPLAY INVISIBLE (-2798 2600);
FORCEADD TAP..6
(-5525 950);
FORCEPROP 3 LASTPIN (-5475 950) SIG_NAME M_B_CLK_DP<3>
J 0
(-5465 960);
DISPLAY 0.659574 (-5465 960);
PAINT MONO (-5465 960);
DISPLAY INVISIBLE (-5465 960);
FORCEPROP 1 LASTPIN (-5475 950) BN 3
J 0
(-5527 958);
DISPLAY 0.617021 (-5527 958);
PAINT PINK (-5527 958);
FORCEPROP 2 LAST CDS_LIB mstr_standard
J 0
(-5525 950);
PAINT MONO (-5525 950);
DISPLAY INVISIBLE (-5525 950);
FORCEPROP 1 LAST BODY_TYPE PLUMBING
J 0
(-5525 900);
DISPLAY 1.595745 (-5525 900);
PAINT GREEN (-5525 900);
DISPLAY INVISIBLE (-5525 900);
FORCEPROP 1 LAST HDL_TAP TRUE
J 0
(-5200 825);
DISPLAY 1.595745 (-5200 825);
PAINT GREEN (-5200 825);
DISPLAY INVISIBLE (-5200 825);
FORCEPROP 1 LAST PATH I12
J 0
(-5527 950);
DISPLAY 0.872340 (-5527 950);
PAINT GREEN (-5527 950);
DISPLAY INVISIBLE (-5527 950);
FORCEADD TAP..6
R 2
(-2800 2550);
FORCEPROP 3 LASTPIN (-2850 2550) SIG_NAME M_B_MA<13>
J 0
(-2840 2560);
DISPLAY 0.659574 (-2840 2560);
PAINT MONO (-2840 2560);
DISPLAY INVISIBLE (-2840 2560);
FORCEPROP 1 LASTPIN (-2850 2550) BN 13
J 2
(-2798 2558);
DISPLAY 0.617021 (-2798 2558);
PAINT PINK (-2798 2558);
FORCEPROP 2 LAST CDS_LIB mstr_standard
J 0
(-2800 2550);
PAINT MONO (-2800 2550);
DISPLAY INVISIBLE (-2800 2550);
FORCEPROP 1 LAST BODY_TYPE PLUMBING
J 2
(-2800 2500);
DISPLAY 1.595745 (-2800 2500);
PAINT GREEN (-2800 2500);
DISPLAY INVISIBLE (-2800 2500);
FORCEPROP 1 LAST HDL_TAP TRUE
J 2
(-3125 2425);
DISPLAY 1.595745 (-3125 2425);
PAINT GREEN (-3125 2425);
DISPLAY INVISIBLE (-3125 2425);
FORCEPROP 1 LAST PATH I120
J 2
(-2798 2550);
DISPLAY 0.872340 (-2798 2550);
PAINT GREEN (-2798 2550);
DISPLAY INVISIBLE (-2798 2550);
FORCEADD TAP..6
R 2
(-2800 2500);
FORCEPROP 3 LASTPIN (-2850 2500) SIG_NAME M_B_MA<12>
J 0
(-2840 2510);
DISPLAY 0.659574 (-2840 2510);
PAINT MONO (-2840 2510);
DISPLAY INVISIBLE (-2840 2510);
FORCEPROP 1 LASTPIN (-2850 2500) BN 12
J 2
(-2798 2508);
DISPLAY 0.617021 (-2798 2508);
PAINT PINK (-2798 2508);
FORCEPROP 2 LAST CDS_LIB mstr_standard
J 0
(-2800 2500);
PAINT MONO (-2800 2500);
DISPLAY INVISIBLE (-2800 2500);
FORCEPROP 1 LAST BODY_TYPE PLUMBING
J 2
(-2800 2450);
DISPLAY 1.595745 (-2800 2450);
PAINT GREEN (-2800 2450);
DISPLAY INVISIBLE (-2800 2450);
FORCEPROP 1 LAST HDL_TAP TRUE
J 2
(-3125 2375);
DISPLAY 1.595745 (-3125 2375);
PAINT GREEN (-3125 2375);
DISPLAY INVISIBLE (-3125 2375);
FORCEPROP 1 LAST PATH I121
J 2
(-2798 2500);
DISPLAY 0.872340 (-2798 2500);
PAINT GREEN (-2798 2500);
DISPLAY INVISIBLE (-2798 2500);
FORCEADD TAP..6
R 2
(-2800 2450);
FORCEPROP 3 LASTPIN (-2850 2450) SIG_NAME M_B_MA<11>
J 0
(-2840 2460);
DISPLAY 0.659574 (-2840 2460);
PAINT MONO (-2840 2460);
DISPLAY INVISIBLE (-2840 2460);
FORCEPROP 1 LASTPIN (-2850 2450) BN 11
J 2
(-2798 2458);
DISPLAY 0.617021 (-2798 2458);
PAINT PINK (-2798 2458);
FORCEPROP 2 LAST CDS_LIB mstr_standard
J 0
(-2800 2450);
PAINT MONO (-2800 2450);
DISPLAY INVISIBLE (-2800 2450);
FORCEPROP 1 LAST BODY_TYPE PLUMBING
J 2
(-2800 2400);
DISPLAY 1.595745 (-2800 2400);
PAINT GREEN (-2800 2400);
DISPLAY INVISIBLE (-2800 2400);
FORCEPROP 1 LAST HDL_TAP TRUE
J 2
(-3125 2325);
DISPLAY 1.595745 (-3125 2325);
PAINT GREEN (-3125 2325);
DISPLAY INVISIBLE (-3125 2325);
FORCEPROP 1 LAST PATH I122
J 2
(-2798 2450);
DISPLAY 0.872340 (-2798 2450);
PAINT GREEN (-2798 2450);
DISPLAY INVISIBLE (-2798 2450);
FORCEADD TAP..6
R 2
(-2800 2850);
FORCEPROP 3 LASTPIN (-2850 2850) SIG_NAME M_B_DQS_DN<0>
J 0
(-2840 2860);
DISPLAY 0.659574 (-2840 2860);
PAINT MONO (-2840 2860);
DISPLAY INVISIBLE (-2840 2860);
FORCEPROP 1 LASTPIN (-2850 2850) BN 0
J 2
(-2798 2858);
DISPLAY 0.617021 (-2798 2858);
PAINT PINK (-2798 2858);
FORCEPROP 2 LAST CDS_LIB mstr_standard
J 0
(-2800 2850);
PAINT MONO (-2800 2850);
DISPLAY INVISIBLE (-2800 2850);
FORCEPROP 1 LAST BODY_TYPE PLUMBING
J 2
(-2800 2800);
DISPLAY 1.595745 (-2800 2800);
PAINT GREEN (-2800 2800);
DISPLAY INVISIBLE (-2800 2800);
FORCEPROP 1 LAST HDL_TAP TRUE
J 2
(-3125 2725);
DISPLAY 1.595745 (-3125 2725);
PAINT GREEN (-3125 2725);
DISPLAY INVISIBLE (-3125 2725);
FORCEPROP 1 LAST PATH I123
J 2
(-2798 2850);
DISPLAY 0.872340 (-2798 2850);
PAINT GREEN (-2798 2850);
DISPLAY INVISIBLE (-2798 2850);
FORCEADD TAP..6
R 2
(-2800 2900);
FORCEPROP 3 LASTPIN (-2850 2900) SIG_NAME M_B_DQS_DN<1>
J 0
(-2840 2910);
DISPLAY 0.659574 (-2840 2910);
PAINT MONO (-2840 2910);
DISPLAY INVISIBLE (-2840 2910);
FORCEPROP 1 LASTPIN (-2850 2900) BN 1
J 2
(-2798 2908);
DISPLAY 0.617021 (-2798 2908);
PAINT PINK (-2798 2908);
FORCEPROP 2 LAST CDS_LIB mstr_standard
J 0
(-2800 2900);
PAINT MONO (-2800 2900);
DISPLAY INVISIBLE (-2800 2900);
FORCEPROP 1 LAST BODY_TYPE PLUMBING
J 2
(-2800 2850);
DISPLAY 1.595745 (-2800 2850);
PAINT GREEN (-2800 2850);
DISPLAY INVISIBLE (-2800 2850);
FORCEPROP 1 LAST HDL_TAP TRUE
J 2
(-3125 2775);
DISPLAY 1.595745 (-3125 2775);
PAINT GREEN (-3125 2775);
DISPLAY INVISIBLE (-3125 2775);
FORCEPROP 1 LAST PATH I124
J 2
(-2798 2900);
DISPLAY 0.872340 (-2798 2900);
PAINT GREEN (-2798 2900);
DISPLAY INVISIBLE (-2798 2900);
FORCEADD TAP..6
R 2
(-2800 2750);
FORCEPROP 3 LASTPIN (-2850 2750) SIG_NAME M_B_MA<17>
J 0
(-2840 2760);
DISPLAY 0.659574 (-2840 2760);
PAINT MONO (-2840 2760);
DISPLAY INVISIBLE (-2840 2760);
FORCEPROP 1 LASTPIN (-2850 2750) BN 17
J 2
(-2798 2758);
DISPLAY 0.617021 (-2798 2758);
PAINT PINK (-2798 2758);
FORCEPROP 2 LAST CDS_LIB mstr_standard
J 0
(-2800 2750);
PAINT MONO (-2800 2750);
DISPLAY INVISIBLE (-2800 2750);
FORCEPROP 1 LAST BODY_TYPE PLUMBING
J 2
(-2800 2700);
DISPLAY 1.595745 (-2800 2700);
PAINT GREEN (-2800 2700);
DISPLAY INVISIBLE (-2800 2700);
FORCEPROP 1 LAST HDL_TAP TRUE
J 2
(-3125 2625);
DISPLAY 1.595745 (-3125 2625);
PAINT GREEN (-3125 2625);
DISPLAY INVISIBLE (-3125 2625);
FORCEPROP 1 LAST PATH I125
J 2
(-2798 2750);
DISPLAY 0.872340 (-2798 2750);
PAINT GREEN (-2798 2750);
DISPLAY INVISIBLE (-2798 2750);
FORCEADD TAP..6
R 2
(-2800 2700);
FORCEPROP 3 LASTPIN (-2850 2700) SIG_NAME M_B_MA<16>
J 0
(-2840 2710);
DISPLAY 0.659574 (-2840 2710);
PAINT MONO (-2840 2710);
DISPLAY INVISIBLE (-2840 2710);
FORCEPROP 1 LASTPIN (-2850 2700) BN 16
J 2
(-2798 2708);
DISPLAY 0.617021 (-2798 2708);
PAINT PINK (-2798 2708);
FORCEPROP 2 LAST CDS_LIB mstr_standard
J 0
(-2800 2700);
PAINT MONO (-2800 2700);
DISPLAY INVISIBLE (-2800 2700);
FORCEPROP 1 LAST BODY_TYPE PLUMBING
J 2
(-2800 2650);
DISPLAY 1.595745 (-2800 2650);
PAINT GREEN (-2800 2650);
DISPLAY INVISIBLE (-2800 2650);
FORCEPROP 1 LAST HDL_TAP TRUE
J 2
(-3125 2575);
DISPLAY 1.595745 (-3125 2575);
PAINT GREEN (-3125 2575);
DISPLAY INVISIBLE (-3125 2575);
FORCEPROP 1 LAST PATH I126
J 2
(-2798 2700);
DISPLAY 0.872340 (-2798 2700);
PAINT GREEN (-2798 2700);
DISPLAY INVISIBLE (-2798 2700);
FORCEADD TAP..6
R 2
(-2800 2950);
FORCEPROP 3 LASTPIN (-2850 2950) SIG_NAME M_B_DQS_DN<2>
J 0
(-2840 2960);
DISPLAY 0.659574 (-2840 2960);
PAINT MONO (-2840 2960);
DISPLAY INVISIBLE (-2840 2960);
FORCEPROP 1 LASTPIN (-2850 2950) BN 2
J 2
(-2798 2958);
DISPLAY 0.617021 (-2798 2958);
PAINT PINK (-2798 2958);
FORCEPROP 2 LAST CDS_LIB mstr_standard
J 0
(-2800 2950);
PAINT MONO (-2800 2950);
DISPLAY INVISIBLE (-2800 2950);
FORCEPROP 1 LAST BODY_TYPE PLUMBING
J 2
(-2800 2900);
DISPLAY 1.595745 (-2800 2900);
PAINT GREEN (-2800 2900);
DISPLAY INVISIBLE (-2800 2900);
FORCEPROP 1 LAST HDL_TAP TRUE
J 2
(-3125 2825);
DISPLAY 1.595745 (-3125 2825);
PAINT GREEN (-3125 2825);
DISPLAY INVISIBLE (-3125 2825);
FORCEPROP 1 LAST PATH I127
J 2
(-2798 2950);
DISPLAY 0.872340 (-2798 2950);
PAINT GREEN (-2798 2950);
DISPLAY INVISIBLE (-2798 2950);
FORCEADD TAP..6
R 2
(-2800 3000);
FORCEPROP 3 LASTPIN (-2850 3000) SIG_NAME M_B_DQS_DN<3>
J 0
(-2840 3010);
DISPLAY 0.659574 (-2840 3010);
PAINT MONO (-2840 3010);
DISPLAY INVISIBLE (-2840 3010);
FORCEPROP 1 LASTPIN (-2850 3000) BN 3
J 2
(-2798 3008);
DISPLAY 0.617021 (-2798 3008);
PAINT PINK (-2798 3008);
FORCEPROP 2 LAST CDS_LIB mstr_standard
J 0
(-2800 3000);
PAINT MONO (-2800 3000);
DISPLAY INVISIBLE (-2800 3000);
FORCEPROP 1 LAST BODY_TYPE PLUMBING
J 2
(-2800 2950);
DISPLAY 1.595745 (-2800 2950);
PAINT GREEN (-2800 2950);
DISPLAY INVISIBLE (-2800 2950);
FORCEPROP 1 LAST HDL_TAP TRUE
J 2
(-3125 2875);
DISPLAY 1.595745 (-3125 2875);
PAINT GREEN (-3125 2875);
DISPLAY INVISIBLE (-3125 2875);
FORCEPROP 1 LAST PATH I128
J 2
(-2798 3000);
DISPLAY 0.872340 (-2798 3000);
PAINT GREEN (-2798 3000);
DISPLAY INVISIBLE (-2798 3000);
FORCEADD TAP..6
R 2
(-2800 3050);
FORCEPROP 3 LASTPIN (-2850 3050) SIG_NAME M_B_DQS_DN<4>
J 0
(-2840 3060);
DISPLAY 0.659574 (-2840 3060);
PAINT MONO (-2840 3060);
DISPLAY INVISIBLE (-2840 3060);
FORCEPROP 1 LASTPIN (-2850 3050) BN 4
J 2
(-2798 3058);
DISPLAY 0.617021 (-2798 3058);
PAINT PINK (-2798 3058);
FORCEPROP 2 LAST CDS_LIB mstr_standard
J 0
(-2800 3050);
PAINT MONO (-2800 3050);
DISPLAY INVISIBLE (-2800 3050);
FORCEPROP 1 LAST BODY_TYPE PLUMBING
J 2
(-2800 3000);
DISPLAY 1.595745 (-2800 3000);
PAINT GREEN (-2800 3000);
DISPLAY INVISIBLE (-2800 3000);
FORCEPROP 1 LAST HDL_TAP TRUE
J 2
(-3125 2925);
DISPLAY 1.595745 (-3125 2925);
PAINT GREEN (-3125 2925);
DISPLAY INVISIBLE (-3125 2925);
FORCEPROP 1 LAST PATH I129
J 2
(-2798 3050);
DISPLAY 0.872340 (-2798 3050);
PAINT GREEN (-2798 3050);
DISPLAY INVISIBLE (-2798 3050);
FORCEADD TAP..6
(-5525 1050);
FORCEPROP 3 LASTPIN (-5475 1050) SIG_NAME M_B_ECC<0>
J 0
(-5465 1060);
DISPLAY 0.659574 (-5465 1060);
PAINT MONO (-5465 1060);
DISPLAY INVISIBLE (-5465 1060);
FORCEPROP 1 LASTPIN (-5475 1050) BN 0
J 0
(-5527 1058);
DISPLAY 0.617021 (-5527 1058);
PAINT PINK (-5527 1058);
FORCEPROP 2 LAST CDS_LIB mstr_standard
J 0
(-5525 1050);
PAINT MONO (-5525 1050);
DISPLAY INVISIBLE (-5525 1050);
FORCEPROP 1 LAST BODY_TYPE PLUMBING
J 0
(-5525 1000);
DISPLAY 1.595745 (-5525 1000);
PAINT GREEN (-5525 1000);
DISPLAY INVISIBLE (-5525 1000);
FORCEPROP 1 LAST HDL_TAP TRUE
J 0
(-5200 925);
DISPLAY 1.595745 (-5200 925);
PAINT GREEN (-5200 925);
DISPLAY INVISIBLE (-5200 925);
FORCEPROP 1 LAST PATH I13
J 0
(-5527 1050);
DISPLAY 0.872340 (-5527 1050);
PAINT GREEN (-5527 1050);
DISPLAY INVISIBLE (-5527 1050);
FORCEADD TAP..6
R 2
(-2800 3150);
FORCEPROP 3 LASTPIN (-2850 3150) SIG_NAME M_B_DQS_DN<6>
J 0
(-2840 3160);
DISPLAY 0.659574 (-2840 3160);
PAINT MONO (-2840 3160);
DISPLAY INVISIBLE (-2840 3160);
FORCEPROP 1 LASTPIN (-2850 3150) BN 6
J 2
(-2798 3158);
DISPLAY 0.617021 (-2798 3158);
PAINT PINK (-2798 3158);
FORCEPROP 2 LAST CDS_LIB mstr_standard
J 0
(-2800 3150);
PAINT MONO (-2800 3150);
DISPLAY INVISIBLE (-2800 3150);
FORCEPROP 1 LAST BODY_TYPE PLUMBING
J 2
(-2800 3100);
DISPLAY 1.595745 (-2800 3100);
PAINT GREEN (-2800 3100);
DISPLAY INVISIBLE (-2800 3100);
FORCEPROP 1 LAST HDL_TAP TRUE
J 2
(-3125 3025);
DISPLAY 1.595745 (-3125 3025);
PAINT GREEN (-3125 3025);
DISPLAY INVISIBLE (-3125 3025);
FORCEPROP 1 LAST PATH I130
J 2
(-2798 3150);
DISPLAY 0.872340 (-2798 3150);
PAINT GREEN (-2798 3150);
DISPLAY INVISIBLE (-2798 3150);
FORCEADD TAP..6
R 2
(-2800 3200);
FORCEPROP 3 LASTPIN (-2850 3200) SIG_NAME M_B_DQS_DN<7>
J 0
(-2840 3210);
DISPLAY 0.659574 (-2840 3210);
PAINT MONO (-2840 3210);
DISPLAY INVISIBLE (-2840 3210);
FORCEPROP 1 LASTPIN (-2850 3200) BN 7
J 2
(-2798 3208);
DISPLAY 0.617021 (-2798 3208);
PAINT PINK (-2798 3208);
FORCEPROP 2 LAST CDS_LIB mstr_standard
J 0
(-2800 3200);
PAINT MONO (-2800 3200);
DISPLAY INVISIBLE (-2800 3200);
FORCEPROP 1 LAST BODY_TYPE PLUMBING
J 2
(-2800 3150);
DISPLAY 1.595745 (-2800 3150);
PAINT GREEN (-2800 3150);
DISPLAY INVISIBLE (-2800 3150);
FORCEPROP 1 LAST HDL_TAP TRUE
J 2
(-3125 3075);
DISPLAY 1.595745 (-3125 3075);
PAINT GREEN (-3125 3075);
DISPLAY INVISIBLE (-3125 3075);
FORCEPROP 1 LAST PATH I131
J 2
(-2798 3200);
DISPLAY 0.872340 (-2798 3200);
PAINT GREEN (-2798 3200);
DISPLAY INVISIBLE (-2798 3200);
FORCEADD TAP..6
R 2
(-2800 3100);
FORCEPROP 3 LASTPIN (-2850 3100) SIG_NAME M_B_DQS_DN<5>
J 0
(-2840 3110);
DISPLAY 0.659574 (-2840 3110);
PAINT MONO (-2840 3110);
DISPLAY INVISIBLE (-2840 3110);
FORCEPROP 1 LASTPIN (-2850 3100) BN 5
J 2
(-2798 3108);
DISPLAY 0.617021 (-2798 3108);
PAINT PINK (-2798 3108);
FORCEPROP 2 LAST CDS_LIB mstr_standard
J 0
(-2800 3100);
PAINT MONO (-2800 3100);
DISPLAY INVISIBLE (-2800 3100);
FORCEPROP 1 LAST BODY_TYPE PLUMBING
J 2
(-2800 3050);
DISPLAY 1.595745 (-2800 3050);
PAINT GREEN (-2800 3050);
DISPLAY INVISIBLE (-2800 3050);
FORCEPROP 1 LAST HDL_TAP TRUE
J 2
(-3125 2975);
DISPLAY 1.595745 (-3125 2975);
PAINT GREEN (-3125 2975);
DISPLAY INVISIBLE (-3125 2975);
FORCEPROP 1 LAST PATH I132
J 2
(-2798 3100);
DISPLAY 0.872340 (-2798 3100);
PAINT GREEN (-2798 3100);
DISPLAY INVISIBLE (-2798 3100);
FORCEADD TAP..6
R 2
(-2800 3250);
FORCEPROP 3 LASTPIN (-2850 3250) SIG_NAME M_B_DQS_DN<8>
J 0
(-2840 3260);
DISPLAY 0.659574 (-2840 3260);
PAINT MONO (-2840 3260);
DISPLAY INVISIBLE (-2840 3260);
FORCEPROP 1 LASTPIN (-2850 3250) BN 8
J 2
(-2798 3258);
DISPLAY 0.617021 (-2798 3258);
PAINT PINK (-2798 3258);
FORCEPROP 2 LAST CDS_LIB mstr_standard
J 0
(-2800 3250);
PAINT MONO (-2800 3250);
DISPLAY INVISIBLE (-2800 3250);
FORCEPROP 1 LAST BODY_TYPE PLUMBING
J 2
(-2800 3200);
DISPLAY 1.595745 (-2800 3200);
PAINT GREEN (-2800 3200);
DISPLAY INVISIBLE (-2800 3200);
FORCEPROP 1 LAST HDL_TAP TRUE
J 2
(-3125 3125);
DISPLAY 1.595745 (-3125 3125);
PAINT GREEN (-3125 3125);
DISPLAY INVISIBLE (-3125 3125);
FORCEPROP 1 LAST PATH I133
J 2
(-2798 3250);
DISPLAY 0.872340 (-2798 3250);
PAINT GREEN (-2798 3250);
DISPLAY INVISIBLE (-2798 3250);
FORCEADD TAP..6
R 2
(-2800 3450);
FORCEPROP 3 LASTPIN (-2850 3450) SIG_NAME M_B_DQS_DN<12>
J 0
(-2840 3460);
DISPLAY 0.659574 (-2840 3460);
PAINT MONO (-2840 3460);
DISPLAY INVISIBLE (-2840 3460);
FORCEPROP 1 LASTPIN (-2850 3450) BN 12
J 2
(-2798 3458);
DISPLAY 0.617021 (-2798 3458);
PAINT PINK (-2798 3458);
FORCEPROP 2 LAST CDS_LIB mstr_standard
J 0
(-2800 3450);
PAINT MONO (-2800 3450);
DISPLAY INVISIBLE (-2800 3450);
FORCEPROP 1 LAST BODY_TYPE PLUMBING
J 2
(-2800 3400);
DISPLAY 1.595745 (-2800 3400);
PAINT GREEN (-2800 3400);
DISPLAY INVISIBLE (-2800 3400);
FORCEPROP 1 LAST HDL_TAP TRUE
J 2
(-3125 3325);
DISPLAY 1.595745 (-3125 3325);
PAINT GREEN (-3125 3325);
DISPLAY INVISIBLE (-3125 3325);
FORCEPROP 1 LAST PATH I134
J 2
(-2798 3450);
DISPLAY 0.872340 (-2798 3450);
PAINT GREEN (-2798 3450);
DISPLAY INVISIBLE (-2798 3450);
FORCEADD TAP..6
R 2
(-2800 3400);
FORCEPROP 3 LASTPIN (-2850 3400) SIG_NAME M_B_DQS_DN<11>
J 0
(-2840 3410);
DISPLAY 0.659574 (-2840 3410);
PAINT MONO (-2840 3410);
DISPLAY INVISIBLE (-2840 3410);
FORCEPROP 1 LASTPIN (-2850 3400) BN 11
J 2
(-2798 3408);
DISPLAY 0.617021 (-2798 3408);
PAINT PINK (-2798 3408);
FORCEPROP 2 LAST CDS_LIB mstr_standard
J 0
(-2800 3400);
PAINT MONO (-2800 3400);
DISPLAY INVISIBLE (-2800 3400);
FORCEPROP 1 LAST BODY_TYPE PLUMBING
J 2
(-2800 3350);
DISPLAY 1.595745 (-2800 3350);
PAINT GREEN (-2800 3350);
DISPLAY INVISIBLE (-2800 3350);
FORCEPROP 1 LAST HDL_TAP TRUE
J 2
(-3125 3275);
DISPLAY 1.595745 (-3125 3275);
PAINT GREEN (-3125 3275);
DISPLAY INVISIBLE (-3125 3275);
FORCEPROP 1 LAST PATH I135
J 2
(-2798 3400);
DISPLAY 0.872340 (-2798 3400);
PAINT GREEN (-2798 3400);
DISPLAY INVISIBLE (-2798 3400);
FORCEADD TAP..6
R 2
(-2800 3300);
FORCEPROP 3 LASTPIN (-2850 3300) SIG_NAME M_B_DQS_DN<9>
J 0
(-2840 3310);
DISPLAY 0.659574 (-2840 3310);
PAINT MONO (-2840 3310);
DISPLAY INVISIBLE (-2840 3310);
FORCEPROP 1 LASTPIN (-2850 3300) BN 9
J 2
(-2798 3308);
DISPLAY 0.617021 (-2798 3308);
PAINT PINK (-2798 3308);
FORCEPROP 2 LAST CDS_LIB mstr_standard
J 0
(-2800 3300);
PAINT MONO (-2800 3300);
DISPLAY INVISIBLE (-2800 3300);
FORCEPROP 1 LAST BODY_TYPE PLUMBING
J 2
(-2800 3250);
DISPLAY 1.595745 (-2800 3250);
PAINT GREEN (-2800 3250);
DISPLAY INVISIBLE (-2800 3250);
FORCEPROP 1 LAST HDL_TAP TRUE
J 2
(-3125 3175);
DISPLAY 1.595745 (-3125 3175);
PAINT GREEN (-3125 3175);
DISPLAY INVISIBLE (-3125 3175);
FORCEPROP 1 LAST PATH I136
J 2
(-2798 3300);
DISPLAY 0.872340 (-2798 3300);
PAINT GREEN (-2798 3300);
DISPLAY INVISIBLE (-2798 3300);
FORCEADD TAP..6
R 2
(-2800 3350);
FORCEPROP 3 LASTPIN (-2850 3350) SIG_NAME M_B_DQS_DN<10>
J 0
(-2840 3360);
DISPLAY 0.659574 (-2840 3360);
PAINT MONO (-2840 3360);
DISPLAY INVISIBLE (-2840 3360);
FORCEPROP 1 LASTPIN (-2850 3350) BN 10
J 2
(-2798 3358);
DISPLAY 0.617021 (-2798 3358);
PAINT PINK (-2798 3358);
FORCEPROP 2 LAST CDS_LIB mstr_standard
J 0
(-2800 3350);
PAINT MONO (-2800 3350);
DISPLAY INVISIBLE (-2800 3350);
FORCEPROP 1 LAST BODY_TYPE PLUMBING
J 2
(-2800 3300);
DISPLAY 1.595745 (-2800 3300);
PAINT GREEN (-2800 3300);
DISPLAY INVISIBLE (-2800 3300);
FORCEPROP 1 LAST HDL_TAP TRUE
J 2
(-3125 3225);
DISPLAY 1.595745 (-3125 3225);
PAINT GREEN (-3125 3225);
DISPLAY INVISIBLE (-3125 3225);
FORCEPROP 1 LAST PATH I137
J 2
(-2798 3350);
DISPLAY 0.872340 (-2798 3350);
PAINT GREEN (-2798 3350);
DISPLAY INVISIBLE (-2798 3350);
FORCEADD TAP..6
R 2
(-2800 3500);
FORCEPROP 3 LASTPIN (-2850 3500) SIG_NAME M_B_DQS_DN<13>
J 0
(-2840 3510);
DISPLAY 0.659574 (-2840 3510);
PAINT MONO (-2840 3510);
DISPLAY INVISIBLE (-2840 3510);
FORCEPROP 1 LASTPIN (-2850 3500) BN 13
J 2
(-2798 3508);
DISPLAY 0.617021 (-2798 3508);
PAINT PINK (-2798 3508);
FORCEPROP 2 LAST CDS_LIB mstr_standard
J 0
(-2800 3500);
PAINT MONO (-2800 3500);
DISPLAY INVISIBLE (-2800 3500);
FORCEPROP 1 LAST BODY_TYPE PLUMBING
J 2
(-2800 3450);
DISPLAY 1.595745 (-2800 3450);
PAINT GREEN (-2800 3450);
DISPLAY INVISIBLE (-2800 3450);
FORCEPROP 1 LAST HDL_TAP TRUE
J 2
(-3125 3375);
DISPLAY 1.595745 (-3125 3375);
PAINT GREEN (-3125 3375);
DISPLAY INVISIBLE (-3125 3375);
FORCEPROP 1 LAST PATH I138
J 2
(-2798 3500);
DISPLAY 0.872340 (-2798 3500);
PAINT GREEN (-2798 3500);
DISPLAY INVISIBLE (-2798 3500);
FORCEADD TAP..6
R 2
(-2800 3700);
FORCEPROP 3 LASTPIN (-2850 3700) SIG_NAME M_B_DQS_DN<17>
J 0
(-2840 3710);
DISPLAY 0.659574 (-2840 3710);
PAINT MONO (-2840 3710);
DISPLAY INVISIBLE (-2840 3710);
FORCEPROP 1 LASTPIN (-2850 3700) BN 17
J 2
(-2798 3708);
DISPLAY 0.617021 (-2798 3708);
PAINT PINK (-2798 3708);
FORCEPROP 2 LAST CDS_LIB mstr_standard
J 0
(-2800 3700);
PAINT MONO (-2800 3700);
DISPLAY INVISIBLE (-2800 3700);
FORCEPROP 1 LAST BODY_TYPE PLUMBING
J 2
(-2800 3650);
DISPLAY 1.595745 (-2800 3650);
PAINT GREEN (-2800 3650);
DISPLAY INVISIBLE (-2800 3650);
FORCEPROP 1 LAST HDL_TAP TRUE
J 2
(-3125 3575);
DISPLAY 1.595745 (-3125 3575);
PAINT GREEN (-3125 3575);
DISPLAY INVISIBLE (-3125 3575);
FORCEPROP 1 LAST PATH I139
J 2
(-2798 3700);
DISPLAY 0.872340 (-2798 3700);
PAINT GREEN (-2798 3700);
DISPLAY INVISIBLE (-2798 3700);
FORCEADD TAP..6
(-5525 1100);
FORCEPROP 3 LASTPIN (-5475 1100) SIG_NAME M_B_ECC<1>
J 0
(-5465 1110);
DISPLAY 0.659574 (-5465 1110);
PAINT MONO (-5465 1110);
DISPLAY INVISIBLE (-5465 1110);
FORCEPROP 1 LASTPIN (-5475 1100) BN 1
J 0
(-5527 1108);
DISPLAY 0.617021 (-5527 1108);
PAINT PINK (-5527 1108);
FORCEPROP 2 LAST CDS_LIB mstr_standard
J 0
(-5525 1100);
PAINT MONO (-5525 1100);
DISPLAY INVISIBLE (-5525 1100);
FORCEPROP 1 LAST BODY_TYPE PLUMBING
J 0
(-5525 1050);
DISPLAY 1.595745 (-5525 1050);
PAINT GREEN (-5525 1050);
DISPLAY INVISIBLE (-5525 1050);
FORCEPROP 1 LAST HDL_TAP TRUE
J 0
(-5200 975);
DISPLAY 1.595745 (-5200 975);
PAINT GREEN (-5200 975);
DISPLAY INVISIBLE (-5200 975);
FORCEPROP 1 LAST PATH I14
J 0
(-5527 1100);
DISPLAY 0.872340 (-5527 1100);
PAINT GREEN (-5527 1100);
DISPLAY INVISIBLE (-5527 1100);
FORCEADD TAP..6
R 2
(-2800 3650);
FORCEPROP 3 LASTPIN (-2850 3650) SIG_NAME M_B_DQS_DN<16>
J 0
(-2840 3660);
DISPLAY 0.659574 (-2840 3660);
PAINT MONO (-2840 3660);
DISPLAY INVISIBLE (-2840 3660);
FORCEPROP 1 LASTPIN (-2850 3650) BN 16
J 2
(-2798 3658);
DISPLAY 0.617021 (-2798 3658);
PAINT PINK (-2798 3658);
FORCEPROP 2 LAST CDS_LIB mstr_standard
J 0
(-2800 3650);
PAINT MONO (-2800 3650);
DISPLAY INVISIBLE (-2800 3650);
FORCEPROP 1 LAST BODY_TYPE PLUMBING
J 2
(-2800 3600);
DISPLAY 1.595745 (-2800 3600);
PAINT GREEN (-2800 3600);
DISPLAY INVISIBLE (-2800 3600);
FORCEPROP 1 LAST HDL_TAP TRUE
J 2
(-3125 3525);
DISPLAY 1.595745 (-3125 3525);
PAINT GREEN (-3125 3525);
DISPLAY INVISIBLE (-3125 3525);
FORCEPROP 1 LAST PATH I140
J 2
(-2798 3650);
DISPLAY 0.872340 (-2798 3650);
PAINT GREEN (-2798 3650);
DISPLAY INVISIBLE (-2798 3650);
FORCEADD TAP..6
R 2
(-2800 3600);
FORCEPROP 3 LASTPIN (-2850 3600) SIG_NAME M_B_DQS_DN<15>
J 0
(-2840 3610);
DISPLAY 0.659574 (-2840 3610);
PAINT MONO (-2840 3610);
DISPLAY INVISIBLE (-2840 3610);
FORCEPROP 1 LASTPIN (-2850 3600) BN 15
J 2
(-2798 3608);
DISPLAY 0.617021 (-2798 3608);
PAINT PINK (-2798 3608);
FORCEPROP 2 LAST CDS_LIB mstr_standard
J 0
(-2800 3600);
PAINT MONO (-2800 3600);
DISPLAY INVISIBLE (-2800 3600);
FORCEPROP 1 LAST BODY_TYPE PLUMBING
J 2
(-2800 3550);
DISPLAY 1.595745 (-2800 3550);
PAINT GREEN (-2800 3550);
DISPLAY INVISIBLE (-2800 3550);
FORCEPROP 1 LAST HDL_TAP TRUE
J 2
(-3125 3475);
DISPLAY 1.595745 (-3125 3475);
PAINT GREEN (-3125 3475);
DISPLAY INVISIBLE (-3125 3475);
FORCEPROP 1 LAST PATH I141
J 2
(-2798 3600);
DISPLAY 0.872340 (-2798 3600);
PAINT GREEN (-2798 3600);
DISPLAY INVISIBLE (-2798 3600);
FORCEADD TAP..6
R 2
(-2800 3550);
FORCEPROP 3 LASTPIN (-2850 3550) SIG_NAME M_B_DQS_DN<14>
J 0
(-2840 3560);
DISPLAY 0.659574 (-2840 3560);
PAINT MONO (-2840 3560);
DISPLAY INVISIBLE (-2840 3560);
FORCEPROP 1 LASTPIN (-2850 3550) BN 14
J 2
(-2798 3558);
DISPLAY 0.617021 (-2798 3558);
PAINT PINK (-2798 3558);
FORCEPROP 2 LAST CDS_LIB mstr_standard
J 0
(-2800 3550);
PAINT MONO (-2800 3550);
DISPLAY INVISIBLE (-2800 3550);
FORCEPROP 1 LAST BODY_TYPE PLUMBING
J 2
(-2800 3500);
DISPLAY 1.595745 (-2800 3500);
PAINT GREEN (-2800 3500);
DISPLAY INVISIBLE (-2800 3500);
FORCEPROP 1 LAST HDL_TAP TRUE
J 2
(-3125 3425);
DISPLAY 1.595745 (-3125 3425);
PAINT GREEN (-3125 3425);
DISPLAY INVISIBLE (-3125 3425);
FORCEPROP 1 LAST PATH I142
J 2
(-2798 3550);
DISPLAY 0.872340 (-2798 3550);
PAINT GREEN (-2798 3550);
DISPLAY INVISIBLE (-2798 3550);
FORCEADD TAP..6
R 2
(-2800 3800);
FORCEPROP 3 LASTPIN (-2850 3800) SIG_NAME M_B_DQS_DP<0>
J 0
(-2840 3810);
DISPLAY 0.659574 (-2840 3810);
PAINT MONO (-2840 3810);
DISPLAY INVISIBLE (-2840 3810);
FORCEPROP 1 LASTPIN (-2850 3800) BN 0
J 2
(-2798 3808);
DISPLAY 0.617021 (-2798 3808);
PAINT PINK (-2798 3808);
FORCEPROP 2 LAST CDS_LIB mstr_standard
J 0
(-2800 3800);
PAINT MONO (-2800 3800);
DISPLAY INVISIBLE (-2800 3800);
FORCEPROP 1 LAST BODY_TYPE PLUMBING
J 2
(-2800 3750);
DISPLAY 1.595745 (-2800 3750);
PAINT GREEN (-2800 3750);
DISPLAY INVISIBLE (-2800 3750);
FORCEPROP 1 LAST HDL_TAP TRUE
J 2
(-3125 3675);
DISPLAY 1.595745 (-3125 3675);
PAINT GREEN (-3125 3675);
DISPLAY INVISIBLE (-3125 3675);
FORCEPROP 1 LAST PATH I143
J 2
(-2798 3800);
DISPLAY 0.872340 (-2798 3800);
PAINT GREEN (-2798 3800);
DISPLAY INVISIBLE (-2798 3800);
FORCEADD TAP..6
R 2
(-2800 3900);
FORCEPROP 3 LASTPIN (-2850 3900) SIG_NAME M_B_DQS_DP<2>
J 0
(-2840 3910);
DISPLAY 0.659574 (-2840 3910);
PAINT MONO (-2840 3910);
DISPLAY INVISIBLE (-2840 3910);
FORCEPROP 1 LASTPIN (-2850 3900) BN 2
J 2
(-2798 3908);
DISPLAY 0.617021 (-2798 3908);
PAINT PINK (-2798 3908);
FORCEPROP 2 LAST CDS_LIB mstr_standard
J 0
(-2800 3900);
PAINT MONO (-2800 3900);
DISPLAY INVISIBLE (-2800 3900);
FORCEPROP 1 LAST BODY_TYPE PLUMBING
J 2
(-2800 3850);
DISPLAY 1.595745 (-2800 3850);
PAINT GREEN (-2800 3850);
DISPLAY INVISIBLE (-2800 3850);
FORCEPROP 1 LAST HDL_TAP TRUE
J 2
(-3125 3775);
DISPLAY 1.595745 (-3125 3775);
PAINT GREEN (-3125 3775);
DISPLAY INVISIBLE (-3125 3775);
FORCEPROP 1 LAST PATH I144
J 2
(-2798 3900);
DISPLAY 0.872340 (-2798 3900);
PAINT GREEN (-2798 3900);
DISPLAY INVISIBLE (-2798 3900);
FORCEADD TAP..6
R 2
(-2800 3950);
FORCEPROP 3 LASTPIN (-2850 3950) SIG_NAME M_B_DQS_DP<3>
J 0
(-2840 3960);
DISPLAY 0.659574 (-2840 3960);
PAINT MONO (-2840 3960);
DISPLAY INVISIBLE (-2840 3960);
FORCEPROP 1 LASTPIN (-2850 3950) BN 3
J 2
(-2798 3958);
DISPLAY 0.617021 (-2798 3958);
PAINT PINK (-2798 3958);
FORCEPROP 2 LAST CDS_LIB mstr_standard
J 0
(-2800 3950);
PAINT MONO (-2800 3950);
DISPLAY INVISIBLE (-2800 3950);
FORCEPROP 1 LAST BODY_TYPE PLUMBING
J 2
(-2800 3900);
DISPLAY 1.595745 (-2800 3900);
PAINT GREEN (-2800 3900);
DISPLAY INVISIBLE (-2800 3900);
FORCEPROP 1 LAST HDL_TAP TRUE
J 2
(-3125 3825);
DISPLAY 1.595745 (-3125 3825);
PAINT GREEN (-3125 3825);
DISPLAY INVISIBLE (-3125 3825);
FORCEPROP 1 LAST PATH I145
J 2
(-2798 3950);
DISPLAY 0.872340 (-2798 3950);
PAINT GREEN (-2798 3950);
DISPLAY INVISIBLE (-2798 3950);
FORCEADD TAP..6
R 2
(-2800 3850);
FORCEPROP 3 LASTPIN (-2850 3850) SIG_NAME M_B_DQS_DP<1>
J 0
(-2840 3860);
DISPLAY 0.659574 (-2840 3860);
PAINT MONO (-2840 3860);
DISPLAY INVISIBLE (-2840 3860);
FORCEPROP 1 LASTPIN (-2850 3850) BN 1
J 2
(-2798 3858);
DISPLAY 0.617021 (-2798 3858);
PAINT PINK (-2798 3858);
FORCEPROP 2 LAST CDS_LIB mstr_standard
J 0
(-2800 3850);
PAINT MONO (-2800 3850);
DISPLAY INVISIBLE (-2800 3850);
FORCEPROP 1 LAST BODY_TYPE PLUMBING
J 2
(-2800 3800);
DISPLAY 1.595745 (-2800 3800);
PAINT GREEN (-2800 3800);
DISPLAY INVISIBLE (-2800 3800);
FORCEPROP 1 LAST HDL_TAP TRUE
J 2
(-3125 3725);
DISPLAY 1.595745 (-3125 3725);
PAINT GREEN (-3125 3725);
DISPLAY INVISIBLE (-3125 3725);
FORCEPROP 1 LAST PATH I146
J 2
(-2798 3850);
DISPLAY 0.872340 (-2798 3850);
PAINT GREEN (-2798 3850);
DISPLAY INVISIBLE (-2798 3850);
FORCEADD OFFPAGE..2
(-1950 500);
FORCEPROP 2 LAST $XR0 45 
J 0
(-1761 500);
DISPLAY 0.638298 (-1761 500);
PAINT MONO (-1761 500);
FORCEPROP 2 LAST $XR1 46 
J 0
(-1671 500);
DISPLAY 0.638298 (-1671 500);
PAINT MONO (-1671 500);
FORCEPROP 2 LAST CDS_LIB mstr_standard
J 0
(-1950 500);
PAINT MONO (-1950 500);
DISPLAY INVISIBLE (-1950 500);
FORCEPROP 1 LAST OFFPAGE TRUE
J 0
(-1625 375);
DISPLAY 1.170213 (-1625 375);
PAINT GREEN (-1625 375);
DISPLAY INVISIBLE (-1625 375);
FORCEPROP 1 LAST COMMENT_BODY TRUE
J 0
(-1995 405);
DISPLAY 1.170213 (-1995 405);
PAINT GREEN (-1995 405);
DISPLAY INVISIBLE (-1995 405);
FORCEPROP 2 LAST PATH I147
J 0
(-1775 575);
DISPLAY 1.021277 (-1775 575);
PAINT ORANGE (-1775 575);
DISPLAY INVISIBLE (-1775 575);
FORCEADD OFFPAGE..4
(-1950 550);
FORCEPROP 2 LAST $XR0 45 
J 0
(-1764 550);
DISPLAY 0.638298 (-1764 550);
PAINT MONO (-1764 550);
FORCEPROP 2 LAST $XR1 46 
J 0
(-1674 550);
DISPLAY 0.638298 (-1674 550);
PAINT MONO (-1674 550);
FORCEPROP 2 LAST CDS_LIB mstr_standard
J 0
(-1950 550);
PAINT MONO (-1950 550);
DISPLAY INVISIBLE (-1950 550);
FORCEPROP 1 LAST OFFPAGE TRUE
J 0
(-1625 425);
DISPLAY 1.170213 (-1625 425);
PAINT GREEN (-1625 425);
DISPLAY INVISIBLE (-1625 425);
FORCEPROP 1 LAST COMMENT_BODY TRUE
J 0
(-1975 450);
DISPLAY 1.170213 (-1975 450);
PAINT GREEN (-1975 450);
DISPLAY INVISIBLE (-1975 450);
FORCEPROP 2 LAST PATH I148
J 0
(-1775 625);
DISPLAY 1.021277 (-1775 625);
PAINT ORANGE (-1775 625);
DISPLAY INVISIBLE (-1775 625);
FORCEADD OFFPAGE..2
(-1950 600);
FORCEPROP 2 LAST $XR0 45 
J 0
(-1761 600);
DISPLAY 0.638298 (-1761 600);
PAINT MONO (-1761 600);
FORCEPROP 2 LAST $XR1 46 
J 0
(-1671 600);
DISPLAY 0.638298 (-1671 600);
PAINT MONO (-1671 600);
FORCEPROP 2 LAST CDS_LIB mstr_standard
J 0
(-1950 600);
PAINT MONO (-1950 600);
DISPLAY INVISIBLE (-1950 600);
FORCEPROP 1 LAST OFFPAGE TRUE
J 0
(-1625 475);
DISPLAY 1.170213 (-1625 475);
PAINT GREEN (-1625 475);
DISPLAY INVISIBLE (-1625 475);
FORCEPROP 1 LAST COMMENT_BODY TRUE
J 0
(-1995 505);
DISPLAY 1.170213 (-1995 505);
PAINT GREEN (-1995 505);
DISPLAY INVISIBLE (-1995 505);
FORCEPROP 2 LAST PATH I149
J 0
(-1775 675);
DISPLAY 1.021277 (-1775 675);
PAINT ORANGE (-1775 675);
DISPLAY INVISIBLE (-1775 675);
FORCEADD TAP..6
(-5525 1150);
FORCEPROP 3 LASTPIN (-5475 1150) SIG_NAME M_B_ECC<2>
J 0
(-5465 1160);
DISPLAY 0.659574 (-5465 1160);
PAINT MONO (-5465 1160);
DISPLAY INVISIBLE (-5465 1160);
FORCEPROP 1 LASTPIN (-5475 1150) BN 2
J 0
(-5527 1158);
DISPLAY 0.617021 (-5527 1158);
PAINT PINK (-5527 1158);
FORCEPROP 2 LAST CDS_LIB mstr_standard
J 0
(-5525 1150);
PAINT MONO (-5525 1150);
DISPLAY INVISIBLE (-5525 1150);
FORCEPROP 1 LAST BODY_TYPE PLUMBING
J 0
(-5525 1100);
DISPLAY 1.595745 (-5525 1100);
PAINT GREEN (-5525 1100);
DISPLAY INVISIBLE (-5525 1100);
FORCEPROP 1 LAST HDL_TAP TRUE
J 0
(-5200 1025);
DISPLAY 1.595745 (-5200 1025);
PAINT GREEN (-5200 1025);
DISPLAY INVISIBLE (-5200 1025);
FORCEPROP 1 LAST PATH I15
J 0
(-5527 1150);
DISPLAY 0.872340 (-5527 1150);
PAINT GREEN (-5527 1150);
DISPLAY INVISIBLE (-5527 1150);
FORCEADD OFFPAGE..2
(-1950 800);
FORCEPROP 2 LAST $XR0 45 
J 0
(-1761 800);
DISPLAY 0.638298 (-1761 800);
PAINT MONO (-1761 800);
FORCEPROP 2 LAST $XR1 46 
J 0
(-1671 800);
DISPLAY 0.638298 (-1671 800);
PAINT MONO (-1671 800);
FORCEPROP 2 LAST CDS_LIB mstr_standard
J 0
(-1950 800);
PAINT MONO (-1950 800);
DISPLAY INVISIBLE (-1950 800);
FORCEPROP 1 LAST OFFPAGE TRUE
J 0
(-1625 675);
DISPLAY 1.170213 (-1625 675);
PAINT GREEN (-1625 675);
DISPLAY INVISIBLE (-1625 675);
FORCEPROP 1 LAST COMMENT_BODY TRUE
J 0
(-1995 705);
DISPLAY 1.170213 (-1995 705);
PAINT GREEN (-1995 705);
DISPLAY INVISIBLE (-1995 705);
FORCEPROP 2 LAST PATH I150
J 0
(-1775 875);
DISPLAY 1.021277 (-1775 875);
PAINT ORANGE (-1775 875);
DISPLAY INVISIBLE (-1775 875);
FORCEADD OFFPAGE..2
(-1950 900);
FORCEPROP 2 LAST $XR0 45 
J 0
(-1761 900);
DISPLAY 0.638298 (-1761 900);
PAINT MONO (-1761 900);
FORCEPROP 2 LAST $XR1 46 
J 0
(-1671 900);
DISPLAY 0.638298 (-1671 900);
PAINT MONO (-1671 900);
FORCEPROP 2 LAST CDS_LIB mstr_standard
J 0
(-1950 900);
PAINT MONO (-1950 900);
DISPLAY INVISIBLE (-1950 900);
FORCEPROP 1 LAST OFFPAGE TRUE
J 0
(-1625 775);
DISPLAY 1.170213 (-1625 775);
PAINT GREEN (-1625 775);
DISPLAY INVISIBLE (-1625 775);
FORCEPROP 1 LAST COMMENT_BODY TRUE
J 0
(-1995 805);
DISPLAY 1.170213 (-1995 805);
PAINT GREEN (-1995 805);
DISPLAY INVISIBLE (-1995 805);
FORCEPROP 2 LAST PATH I151
J 0
(-1775 975);
DISPLAY 1.021277 (-1775 975);
PAINT ORANGE (-1775 975);
DISPLAY INVISIBLE (-1775 975);
FORCEADD OFFPAGE..2
(-1950 1350);
FORCEPROP 2 LAST $XR0 45 
J 0
(-1761 1350);
DISPLAY 0.638298 (-1761 1350);
PAINT MONO (-1761 1350);
FORCEPROP 2 LAST $XR1 46 
J 0
(-1671 1350);
DISPLAY 0.638298 (-1671 1350);
PAINT MONO (-1671 1350);
FORCEPROP 2 LAST CDS_LIB mstr_standard
J 0
(-1950 1350);
PAINT MONO (-1950 1350);
DISPLAY INVISIBLE (-1950 1350);
FORCEPROP 1 LAST OFFPAGE TRUE
J 0
(-1625 1225);
DISPLAY 1.170213 (-1625 1225);
PAINT GREEN (-1625 1225);
DISPLAY INVISIBLE (-1625 1225);
FORCEPROP 1 LAST COMMENT_BODY TRUE
J 0
(-1995 1255);
DISPLAY 1.170213 (-1995 1255);
PAINT GREEN (-1995 1255);
DISPLAY INVISIBLE (-1995 1255);
FORCEPROP 2 LAST PATH I152
J 0
(-1775 1425);
DISPLAY 1.021277 (-1775 1425);
PAINT ORANGE (-1775 1425);
DISPLAY INVISIBLE (-1775 1425);
FORCEADD OFFPAGE..2
(-1950 1600);
FORCEPROP 2 LAST $XR0 45 
J 0
(-1761 1600);
DISPLAY 0.638298 (-1761 1600);
PAINT MONO (-1761 1600);
FORCEPROP 2 LAST $XR1 46 
J 0
(-1671 1600);
DISPLAY 0.638298 (-1671 1600);
PAINT MONO (-1671 1600);
FORCEPROP 2 LAST CDS_LIB mstr_standard
J 0
(-1950 1600);
PAINT MONO (-1950 1600);
DISPLAY INVISIBLE (-1950 1600);
FORCEPROP 1 LAST OFFPAGE TRUE
J 0
(-1625 1475);
DISPLAY 1.170213 (-1625 1475);
PAINT GREEN (-1625 1475);
DISPLAY INVISIBLE (-1625 1475);
FORCEPROP 1 LAST COMMENT_BODY TRUE
J 0
(-1995 1505);
DISPLAY 1.170213 (-1995 1505);
PAINT GREEN (-1995 1505);
DISPLAY INVISIBLE (-1995 1505);
FORCEPROP 2 LAST PATH I153
J 0
(-1775 1675);
DISPLAY 1.021277 (-1775 1675);
PAINT ORANGE (-1775 1675);
DISPLAY INVISIBLE (-1775 1675);
FORCEADD OFFPAGE..2
(-1950 1850);
FORCEPROP 2 LAST $XR0 45 
J 0
(-1761 1850);
DISPLAY 0.638298 (-1761 1850);
PAINT MONO (-1761 1850);
FORCEPROP 2 LAST $XR1 46 
J 0
(-1671 1850);
DISPLAY 0.638298 (-1671 1850);
PAINT MONO (-1671 1850);
FORCEPROP 2 LAST CDS_LIB mstr_standard
J 0
(-1950 1850);
PAINT MONO (-1950 1850);
DISPLAY INVISIBLE (-1950 1850);
FORCEPROP 1 LAST OFFPAGE TRUE
J 0
(-1625 1725);
DISPLAY 1.170213 (-1625 1725);
PAINT GREEN (-1625 1725);
DISPLAY INVISIBLE (-1625 1725);
FORCEPROP 1 LAST COMMENT_BODY TRUE
J 0
(-1995 1755);
DISPLAY 1.170213 (-1995 1755);
PAINT GREEN (-1995 1755);
DISPLAY INVISIBLE (-1995 1755);
FORCEPROP 2 LAST PATH I154
J 0
(-1775 1925);
DISPLAY 1.021277 (-1775 1925);
PAINT ORANGE (-1775 1925);
DISPLAY INVISIBLE (-1775 1925);
FORCEADD OFFPAGE..2
(-1950 2800);
FORCEPROP 2 LAST $XR0 45 
J 0
(-1761 2800);
DISPLAY 0.638298 (-1761 2800);
PAINT MONO (-1761 2800);
FORCEPROP 2 LAST $XR1 46 
J 0
(-1671 2800);
DISPLAY 0.638298 (-1671 2800);
PAINT MONO (-1671 2800);
FORCEPROP 2 LAST CDS_LIB mstr_standard
J 0
(-1950 2800);
PAINT MONO (-1950 2800);
DISPLAY INVISIBLE (-1950 2800);
FORCEPROP 1 LAST OFFPAGE TRUE
J 0
(-1625 2675);
DISPLAY 1.170213 (-1625 2675);
PAINT GREEN (-1625 2675);
DISPLAY INVISIBLE (-1625 2675);
FORCEPROP 1 LAST COMMENT_BODY TRUE
J 0
(-1995 2705);
DISPLAY 1.170213 (-1995 2705);
PAINT GREEN (-1995 2705);
DISPLAY INVISIBLE (-1995 2705);
FORCEPROP 2 LAST PATH I155
J 0
(-1775 2875);
DISPLAY 1.021277 (-1775 2875);
PAINT ORANGE (-1775 2875);
DISPLAY INVISIBLE (-1775 2875);
FORCEADD OFFPAGE..3
(-1950 3750);
FORCEPROP 2 LAST $XR0 45 
J 0
(-1736 3750);
DISPLAY 0.638298 (-1736 3750);
PAINT MONO (-1736 3750);
FORCEPROP 2 LAST $XR1 46 
J 0
(-1646 3750);
DISPLAY 0.638298 (-1646 3750);
PAINT MONO (-1646 3750);
FORCEPROP 2 LAST CDS_LIB mstr_standard
J 0
(-1950 3750);
PAINT MONO (-1950 3750);
DISPLAY INVISIBLE (-1950 3750);
FORCEPROP 1 LAST OFFPAGE TRUE
J 0
(-1625 3625);
DISPLAY 1.170213 (-1625 3625);
PAINT GREEN (-1625 3625);
DISPLAY INVISIBLE (-1625 3625);
FORCEPROP 1 LAST COMMENT_BODY TRUE
J 0
(-2000 3650);
DISPLAY 1.170213 (-2000 3650);
PAINT GREEN (-2000 3650);
DISPLAY INVISIBLE (-2000 3650);
FORCEPROP 2 LAST PATH I156
J 0
(-1750 3825);
DISPLAY 1.021277 (-1750 3825);
PAINT ORANGE (-1750 3825);
DISPLAY INVISIBLE (-1750 3825);
FORCEADD TAP..6
R 2
(-2800 4150);
FORCEPROP 3 LASTPIN (-2850 4150) SIG_NAME M_B_DQS_DP<7>
J 0
(-2840 4160);
DISPLAY 0.659574 (-2840 4160);
PAINT MONO (-2840 4160);
DISPLAY INVISIBLE (-2840 4160);
FORCEPROP 1 LASTPIN (-2850 4150) BN 7
J 2
(-2798 4158);
DISPLAY 0.617021 (-2798 4158);
PAINT PINK (-2798 4158);
FORCEPROP 2 LAST CDS_LIB mstr_standard
J 0
(-2800 4150);
PAINT MONO (-2800 4150);
DISPLAY INVISIBLE (-2800 4150);
FORCEPROP 1 LAST BODY_TYPE PLUMBING
J 2
(-2800 4100);
DISPLAY 1.595745 (-2800 4100);
PAINT GREEN (-2800 4100);
DISPLAY INVISIBLE (-2800 4100);
FORCEPROP 1 LAST HDL_TAP TRUE
J 2
(-3125 4025);
DISPLAY 1.595745 (-3125 4025);
PAINT GREEN (-3125 4025);
DISPLAY INVISIBLE (-3125 4025);
FORCEPROP 1 LAST PATH I157
J 2
(-2798 4150);
DISPLAY 0.872340 (-2798 4150);
PAINT GREEN (-2798 4150);
DISPLAY INVISIBLE (-2798 4150);
FORCEADD TAP..6
R 2
(-2800 4200);
FORCEPROP 3 LASTPIN (-2850 4200) SIG_NAME M_B_DQS_DP<8>
J 0
(-2840 4210);
DISPLAY 0.659574 (-2840 4210);
PAINT MONO (-2840 4210);
DISPLAY INVISIBLE (-2840 4210);
FORCEPROP 1 LASTPIN (-2850 4200) BN 8
J 2
(-2798 4208);
DISPLAY 0.617021 (-2798 4208);
PAINT PINK (-2798 4208);
FORCEPROP 2 LAST CDS_LIB mstr_standard
J 0
(-2800 4200);
PAINT MONO (-2800 4200);
DISPLAY INVISIBLE (-2800 4200);
FORCEPROP 1 LAST BODY_TYPE PLUMBING
J 2
(-2800 4150);
DISPLAY 1.595745 (-2800 4150);
PAINT GREEN (-2800 4150);
DISPLAY INVISIBLE (-2800 4150);
FORCEPROP 1 LAST HDL_TAP TRUE
J 2
(-3125 4075);
DISPLAY 1.595745 (-3125 4075);
PAINT GREEN (-3125 4075);
DISPLAY INVISIBLE (-3125 4075);
FORCEPROP 1 LAST PATH I158
J 2
(-2798 4200);
DISPLAY 0.872340 (-2798 4200);
PAINT GREEN (-2798 4200);
DISPLAY INVISIBLE (-2798 4200);
FORCEADD TAP..6
R 2
(-2800 4050);
FORCEPROP 3 LASTPIN (-2850 4050) SIG_NAME M_B_DQS_DP<5>
J 0
(-2840 4060);
DISPLAY 0.659574 (-2840 4060);
PAINT MONO (-2840 4060);
DISPLAY INVISIBLE (-2840 4060);
FORCEPROP 1 LASTPIN (-2850 4050) BN 5
J 2
(-2798 4058);
DISPLAY 0.617021 (-2798 4058);
PAINT PINK (-2798 4058);
FORCEPROP 2 LAST CDS_LIB mstr_standard
J 0
(-2800 4050);
PAINT MONO (-2800 4050);
DISPLAY INVISIBLE (-2800 4050);
FORCEPROP 1 LAST BODY_TYPE PLUMBING
J 2
(-2800 4000);
DISPLAY 1.595745 (-2800 4000);
PAINT GREEN (-2800 4000);
DISPLAY INVISIBLE (-2800 4000);
FORCEPROP 1 LAST HDL_TAP TRUE
J 2
(-3125 3925);
DISPLAY 1.595745 (-3125 3925);
PAINT GREEN (-3125 3925);
DISPLAY INVISIBLE (-3125 3925);
FORCEPROP 1 LAST PATH I159
J 2
(-2798 4050);
DISPLAY 0.872340 (-2798 4050);
PAINT GREEN (-2798 4050);
DISPLAY INVISIBLE (-2798 4050);
FORCEADD TAP..6
(-5525 1250);
FORCEPROP 3 LASTPIN (-5475 1250) SIG_NAME M_B_ECC<4>
J 0
(-5465 1260);
DISPLAY 0.659574 (-5465 1260);
PAINT MONO (-5465 1260);
DISPLAY INVISIBLE (-5465 1260);
FORCEPROP 1 LASTPIN (-5475 1250) BN 4
J 0
(-5527 1258);
DISPLAY 0.617021 (-5527 1258);
PAINT PINK (-5527 1258);
FORCEPROP 2 LAST CDS_LIB mstr_standard
J 0
(-5525 1250);
PAINT MONO (-5525 1250);
DISPLAY INVISIBLE (-5525 1250);
FORCEPROP 1 LAST BODY_TYPE PLUMBING
J 0
(-5525 1200);
DISPLAY 1.595745 (-5525 1200);
PAINT GREEN (-5525 1200);
DISPLAY INVISIBLE (-5525 1200);
FORCEPROP 1 LAST HDL_TAP TRUE
J 0
(-5200 1125);
DISPLAY 1.595745 (-5200 1125);
PAINT GREEN (-5200 1125);
DISPLAY INVISIBLE (-5200 1125);
FORCEPROP 1 LAST PATH I16
J 0
(-5527 1250);
DISPLAY 0.872340 (-5527 1250);
PAINT GREEN (-5527 1250);
DISPLAY INVISIBLE (-5527 1250);
FORCEADD TAP..6
R 2
(-2800 4100);
FORCEPROP 3 LASTPIN (-2850 4100) SIG_NAME M_B_DQS_DP<6>
J 0
(-2840 4110);
DISPLAY 0.659574 (-2840 4110);
PAINT MONO (-2840 4110);
DISPLAY INVISIBLE (-2840 4110);
FORCEPROP 1 LASTPIN (-2850 4100) BN 6
J 2
(-2798 4108);
DISPLAY 0.617021 (-2798 4108);
PAINT PINK (-2798 4108);
FORCEPROP 2 LAST CDS_LIB mstr_standard
J 0
(-2800 4100);
PAINT MONO (-2800 4100);
DISPLAY INVISIBLE (-2800 4100);
FORCEPROP 1 LAST BODY_TYPE PLUMBING
J 2
(-2800 4050);
DISPLAY 1.595745 (-2800 4050);
PAINT GREEN (-2800 4050);
DISPLAY INVISIBLE (-2800 4050);
FORCEPROP 1 LAST HDL_TAP TRUE
J 2
(-3125 3975);
DISPLAY 1.595745 (-3125 3975);
PAINT GREEN (-3125 3975);
DISPLAY INVISIBLE (-3125 3975);
FORCEPROP 1 LAST PATH I160
J 2
(-2798 4100);
DISPLAY 0.872340 (-2798 4100);
PAINT GREEN (-2798 4100);
DISPLAY INVISIBLE (-2798 4100);
FORCEADD TAP..6
R 2
(-2800 4000);
FORCEPROP 3 LASTPIN (-2850 4000) SIG_NAME M_B_DQS_DP<4>
J 0
(-2840 4010);
DISPLAY 0.659574 (-2840 4010);
PAINT MONO (-2840 4010);
DISPLAY INVISIBLE (-2840 4010);
FORCEPROP 1 LASTPIN (-2850 4000) BN 4
J 2
(-2798 4008);
DISPLAY 0.617021 (-2798 4008);
PAINT PINK (-2798 4008);
FORCEPROP 2 LAST CDS_LIB mstr_standard
J 0
(-2800 4000);
PAINT MONO (-2800 4000);
DISPLAY INVISIBLE (-2800 4000);
FORCEPROP 1 LAST BODY_TYPE PLUMBING
J 2
(-2800 3950);
DISPLAY 1.595745 (-2800 3950);
PAINT GREEN (-2800 3950);
DISPLAY INVISIBLE (-2800 3950);
FORCEPROP 1 LAST HDL_TAP TRUE
J 2
(-3125 3875);
DISPLAY 1.595745 (-3125 3875);
PAINT GREEN (-3125 3875);
DISPLAY INVISIBLE (-3125 3875);
FORCEPROP 1 LAST PATH I161
J 2
(-2798 4000);
DISPLAY 0.872340 (-2798 4000);
PAINT GREEN (-2798 4000);
DISPLAY INVISIBLE (-2798 4000);
FORCEADD TAP..6
R 2
(-2800 4450);
FORCEPROP 3 LASTPIN (-2850 4450) SIG_NAME M_B_DQS_DP<13>
J 0
(-2840 4460);
DISPLAY 0.659574 (-2840 4460);
PAINT MONO (-2840 4460);
DISPLAY INVISIBLE (-2840 4460);
FORCEPROP 1 LASTPIN (-2850 4450) BN 13
J 2
(-2798 4458);
DISPLAY 0.617021 (-2798 4458);
PAINT PINK (-2798 4458);
FORCEPROP 2 LAST CDS_LIB mstr_standard
J 0
(-2800 4450);
PAINT MONO (-2800 4450);
DISPLAY INVISIBLE (-2800 4450);
FORCEPROP 1 LAST BODY_TYPE PLUMBING
J 2
(-2800 4400);
DISPLAY 1.595745 (-2800 4400);
PAINT GREEN (-2800 4400);
DISPLAY INVISIBLE (-2800 4400);
FORCEPROP 1 LAST HDL_TAP TRUE
J 2
(-3125 4325);
DISPLAY 1.595745 (-3125 4325);
PAINT GREEN (-3125 4325);
DISPLAY INVISIBLE (-3125 4325);
FORCEPROP 1 LAST PATH I162
J 2
(-2798 4450);
DISPLAY 0.872340 (-2798 4450);
PAINT GREEN (-2798 4450);
DISPLAY INVISIBLE (-2798 4450);
FORCEADD TAP..6
R 2
(-2800 4400);
FORCEPROP 3 LASTPIN (-2850 4400) SIG_NAME M_B_DQS_DP<12>
J 0
(-2840 4410);
DISPLAY 0.659574 (-2840 4410);
PAINT MONO (-2840 4410);
DISPLAY INVISIBLE (-2840 4410);
FORCEPROP 1 LASTPIN (-2850 4400) BN 12
J 2
(-2798 4408);
DISPLAY 0.617021 (-2798 4408);
PAINT PINK (-2798 4408);
FORCEPROP 2 LAST CDS_LIB mstr_standard
J 0
(-2800 4400);
PAINT MONO (-2800 4400);
DISPLAY INVISIBLE (-2800 4400);
FORCEPROP 1 LAST BODY_TYPE PLUMBING
J 2
(-2800 4350);
DISPLAY 1.595745 (-2800 4350);
PAINT GREEN (-2800 4350);
DISPLAY INVISIBLE (-2800 4350);
FORCEPROP 1 LAST HDL_TAP TRUE
J 2
(-3125 4275);
DISPLAY 1.595745 (-3125 4275);
PAINT GREEN (-3125 4275);
DISPLAY INVISIBLE (-3125 4275);
FORCEPROP 1 LAST PATH I163
J 2
(-2798 4400);
DISPLAY 0.872340 (-2798 4400);
PAINT GREEN (-2798 4400);
DISPLAY INVISIBLE (-2798 4400);
FORCEADD TAP..6
R 2
(-2800 4350);
FORCEPROP 3 LASTPIN (-2850 4350) SIG_NAME M_B_DQS_DP<11>
J 0
(-2840 4360);
DISPLAY 0.659574 (-2840 4360);
PAINT MONO (-2840 4360);
DISPLAY INVISIBLE (-2840 4360);
FORCEPROP 1 LASTPIN (-2850 4350) BN 11
J 2
(-2798 4358);
DISPLAY 0.617021 (-2798 4358);
PAINT PINK (-2798 4358);
FORCEPROP 2 LAST CDS_LIB mstr_standard
J 0
(-2800 4350);
PAINT MONO (-2800 4350);
DISPLAY INVISIBLE (-2800 4350);
FORCEPROP 1 LAST BODY_TYPE PLUMBING
J 2
(-2800 4300);
DISPLAY 1.595745 (-2800 4300);
PAINT GREEN (-2800 4300);
DISPLAY INVISIBLE (-2800 4300);
FORCEPROP 1 LAST HDL_TAP TRUE
J 2
(-3125 4225);
DISPLAY 1.595745 (-3125 4225);
PAINT GREEN (-3125 4225);
DISPLAY INVISIBLE (-3125 4225);
FORCEPROP 1 LAST PATH I164
J 2
(-2798 4350);
DISPLAY 0.872340 (-2798 4350);
PAINT GREEN (-2798 4350);
DISPLAY INVISIBLE (-2798 4350);
FORCEADD TAP..6
R 2
(-2800 4300);
FORCEPROP 3 LASTPIN (-2850 4300) SIG_NAME M_B_DQS_DP<10>
J 0
(-2840 4310);
DISPLAY 0.659574 (-2840 4310);
PAINT MONO (-2840 4310);
DISPLAY INVISIBLE (-2840 4310);
FORCEPROP 1 LASTPIN (-2850 4300) BN 10
J 2
(-2798 4308);
DISPLAY 0.617021 (-2798 4308);
PAINT PINK (-2798 4308);
FORCEPROP 2 LAST CDS_LIB mstr_standard
J 0
(-2800 4300);
PAINT MONO (-2800 4300);
DISPLAY INVISIBLE (-2800 4300);
FORCEPROP 1 LAST BODY_TYPE PLUMBING
J 2
(-2800 4250);
DISPLAY 1.595745 (-2800 4250);
PAINT GREEN (-2800 4250);
DISPLAY INVISIBLE (-2800 4250);
FORCEPROP 1 LAST HDL_TAP TRUE
J 2
(-3125 4175);
DISPLAY 1.595745 (-3125 4175);
PAINT GREEN (-3125 4175);
DISPLAY INVISIBLE (-3125 4175);
FORCEPROP 1 LAST PATH I165
J 2
(-2798 4300);
DISPLAY 0.872340 (-2798 4300);
PAINT GREEN (-2798 4300);
DISPLAY INVISIBLE (-2798 4300);
FORCEADD TAP..6
R 2
(-2800 4250);
FORCEPROP 3 LASTPIN (-2850 4250) SIG_NAME M_B_DQS_DP<9>
J 0
(-2840 4260);
DISPLAY 0.659574 (-2840 4260);
PAINT MONO (-2840 4260);
DISPLAY INVISIBLE (-2840 4260);
FORCEPROP 1 LASTPIN (-2850 4250) BN 9
J 2
(-2798 4258);
DISPLAY 0.617021 (-2798 4258);
PAINT PINK (-2798 4258);
FORCEPROP 2 LAST CDS_LIB mstr_standard
J 0
(-2800 4250);
PAINT MONO (-2800 4250);
DISPLAY INVISIBLE (-2800 4250);
FORCEPROP 1 LAST BODY_TYPE PLUMBING
J 2
(-2800 4200);
DISPLAY 1.595745 (-2800 4200);
PAINT GREEN (-2800 4200);
DISPLAY INVISIBLE (-2800 4200);
FORCEPROP 1 LAST HDL_TAP TRUE
J 2
(-3125 4125);
DISPLAY 1.595745 (-3125 4125);
PAINT GREEN (-3125 4125);
DISPLAY INVISIBLE (-3125 4125);
FORCEPROP 1 LAST PATH I166
J 2
(-2798 4250);
DISPLAY 0.872340 (-2798 4250);
PAINT GREEN (-2798 4250);
DISPLAY INVISIBLE (-2798 4250);
FORCEADD TAP..6
R 2
(-2800 4600);
FORCEPROP 3 LASTPIN (-2850 4600) SIG_NAME M_B_DQS_DP<16>
J 0
(-2840 4610);
DISPLAY 0.659574 (-2840 4610);
PAINT MONO (-2840 4610);
DISPLAY INVISIBLE (-2840 4610);
FORCEPROP 1 LASTPIN (-2850 4600) BN 16
J 2
(-2798 4608);
DISPLAY 0.617021 (-2798 4608);
PAINT PINK (-2798 4608);
FORCEPROP 2 LAST CDS_LIB mstr_standard
J 0
(-2800 4600);
PAINT MONO (-2800 4600);
DISPLAY INVISIBLE (-2800 4600);
FORCEPROP 1 LAST BODY_TYPE PLUMBING
J 2
(-2800 4550);
DISPLAY 1.595745 (-2800 4550);
PAINT GREEN (-2800 4550);
DISPLAY INVISIBLE (-2800 4550);
FORCEPROP 1 LAST HDL_TAP TRUE
J 2
(-3125 4475);
DISPLAY 1.595745 (-3125 4475);
PAINT GREEN (-3125 4475);
DISPLAY INVISIBLE (-3125 4475);
FORCEPROP 1 LAST PATH I167
J 2
(-2798 4600);
DISPLAY 0.872340 (-2798 4600);
PAINT GREEN (-2798 4600);
DISPLAY INVISIBLE (-2798 4600);
FORCEADD TAP..6
R 2
(-2800 4650);
FORCEPROP 3 LASTPIN (-2850 4650) SIG_NAME M_B_DQS_DP<17>
J 0
(-2840 4660);
DISPLAY 0.659574 (-2840 4660);
PAINT MONO (-2840 4660);
DISPLAY INVISIBLE (-2840 4660);
FORCEPROP 1 LASTPIN (-2850 4650) BN 17
J 2
(-2798 4658);
DISPLAY 0.617021 (-2798 4658);
PAINT PINK (-2798 4658);
FORCEPROP 2 LAST CDS_LIB mstr_standard
J 2
(-2800 4650);
PAINT MONO (-2800 4650);
DISPLAY INVISIBLE (-2800 4650);
FORCEPROP 1 LAST BODY_TYPE PLUMBING
J 2
(-2800 4600);
DISPLAY 1.595745 (-2800 4600);
PAINT GREEN (-2800 4600);
DISPLAY INVISIBLE (-2800 4600);
FORCEPROP 1 LAST HDL_TAP TRUE
J 2
(-3125 4525);
DISPLAY 1.595745 (-3125 4525);
PAINT GREEN (-3125 4525);
DISPLAY INVISIBLE (-3125 4525);
FORCEPROP 1 LAST PATH I168
J 2
(-2798 4650);
DISPLAY 0.872340 (-2798 4650);
PAINT GREEN (-2798 4650);
DISPLAY INVISIBLE (-2798 4650);
FORCEADD TAP..6
R 2
(-2800 4550);
FORCEPROP 3 LASTPIN (-2850 4550) SIG_NAME M_B_DQS_DP<15>
J 0
(-2840 4560);
DISPLAY 0.659574 (-2840 4560);
PAINT MONO (-2840 4560);
DISPLAY INVISIBLE (-2840 4560);
FORCEPROP 1 LASTPIN (-2850 4550) BN 15
J 2
(-2798 4558);
DISPLAY 0.617021 (-2798 4558);
PAINT PINK (-2798 4558);
FORCEPROP 2 LAST CDS_LIB mstr_standard
J 0
(-2800 4550);
PAINT MONO (-2800 4550);
DISPLAY INVISIBLE (-2800 4550);
FORCEPROP 1 LAST BODY_TYPE PLUMBING
J 2
(-2800 4500);
DISPLAY 1.595745 (-2800 4500);
PAINT GREEN (-2800 4500);
DISPLAY INVISIBLE (-2800 4500);
FORCEPROP 1 LAST HDL_TAP TRUE
J 2
(-3125 4425);
DISPLAY 1.595745 (-3125 4425);
PAINT GREEN (-3125 4425);
DISPLAY INVISIBLE (-3125 4425);
FORCEPROP 1 LAST PATH I169
J 2
(-2798 4550);
DISPLAY 0.872340 (-2798 4550);
PAINT GREEN (-2798 4550);
DISPLAY INVISIBLE (-2798 4550);
FORCEADD TAP..6
(-5525 1200);
FORCEPROP 3 LASTPIN (-5475 1200) SIG_NAME M_B_ECC<3>
J 0
(-5465 1210);
DISPLAY 0.659574 (-5465 1210);
PAINT MONO (-5465 1210);
DISPLAY INVISIBLE (-5465 1210);
FORCEPROP 1 LASTPIN (-5475 1200) BN 3
J 0
(-5527 1208);
DISPLAY 0.617021 (-5527 1208);
PAINT PINK (-5527 1208);
FORCEPROP 2 LAST CDS_LIB mstr_standard
J 0
(-5525 1200);
PAINT MONO (-5525 1200);
DISPLAY INVISIBLE (-5525 1200);
FORCEPROP 1 LAST BODY_TYPE PLUMBING
J 0
(-5525 1150);
DISPLAY 1.595745 (-5525 1150);
PAINT GREEN (-5525 1150);
DISPLAY INVISIBLE (-5525 1150);
FORCEPROP 1 LAST HDL_TAP TRUE
J 0
(-5200 1075);
DISPLAY 1.595745 (-5200 1075);
PAINT GREEN (-5200 1075);
DISPLAY INVISIBLE (-5200 1075);
FORCEPROP 1 LAST PATH I17
J 0
(-5527 1200);
DISPLAY 0.872340 (-5527 1200);
PAINT GREEN (-5527 1200);
DISPLAY INVISIBLE (-5527 1200);
FORCEADD TAP..6
R 2
(-2800 4500);
FORCEPROP 3 LASTPIN (-2850 4500) SIG_NAME M_B_DQS_DP<14>
J 0
(-2840 4510);
DISPLAY 0.659574 (-2840 4510);
PAINT MONO (-2840 4510);
DISPLAY INVISIBLE (-2840 4510);
FORCEPROP 1 LASTPIN (-2850 4500) BN 14
J 2
(-2798 4508);
DISPLAY 0.617021 (-2798 4508);
PAINT PINK (-2798 4508);
FORCEPROP 2 LAST CDS_LIB mstr_standard
J 0
(-2800 4500);
PAINT MONO (-2800 4500);
DISPLAY INVISIBLE (-2800 4500);
FORCEPROP 1 LAST BODY_TYPE PLUMBING
J 2
(-2800 4450);
DISPLAY 1.595745 (-2800 4450);
PAINT GREEN (-2800 4450);
DISPLAY INVISIBLE (-2800 4450);
FORCEPROP 1 LAST HDL_TAP TRUE
J 2
(-3125 4375);
DISPLAY 1.595745 (-3125 4375);
PAINT GREEN (-3125 4375);
DISPLAY INVISIBLE (-3125 4375);
FORCEPROP 1 LAST PATH I170
J 2
(-2798 4500);
DISPLAY 0.872340 (-2798 4500);
PAINT GREEN (-2798 4500);
DISPLAY INVISIBLE (-2798 4500);
FORCEADD OFFPAGE..3
(-1950 4725);
FORCEPROP 2 LAST $XR0 45 
J 0
(-1736 4725);
DISPLAY 0.638298 (-1736 4725);
PAINT MONO (-1736 4725);
FORCEPROP 2 LAST $XR1 46 
J 0
(-1646 4725);
DISPLAY 0.638298 (-1646 4725);
PAINT MONO (-1646 4725);
FORCEPROP 2 LAST CDS_LIB mstr_standard
J 0
(-1950 4725);
PAINT MONO (-1950 4725);
DISPLAY INVISIBLE (-1950 4725);
FORCEPROP 1 LAST OFFPAGE TRUE
J 0
(-1625 4600);
DISPLAY 1.170213 (-1625 4600);
PAINT GREEN (-1625 4600);
DISPLAY INVISIBLE (-1625 4600);
FORCEPROP 1 LAST COMMENT_BODY TRUE
J 0
(-2000 4625);
DISPLAY 1.170213 (-2000 4625);
PAINT GREEN (-2000 4625);
DISPLAY INVISIBLE (-2000 4625);
FORCEPROP 2 LAST PATH I171
J 0
(-1750 4800);
DISPLAY 1.021277 (-1750 4800);
PAINT ORANGE (-1750 4800);
DISPLAY INVISIBLE (-1750 4800);
FORCEADD SKX_EXT_B..4
(-4125 2550);
FORCEPROP 1 LAST LOCATION U5D1
J 0
(-4925 4900);
DISPLAY 0.617021 (-4925 4900);
PAINT AQUA (-4925 4900);
FORCEPROP 1 LAST PART_NUMBER TBD
J 0
(-4925 300);
DISPLAY 0.617021 (-4925 300);
PAINT BLUE (-4925 300);
FORCEPROP 1 LAST MATERIAL IC
J 0
(-4925 4850);
DISPLAY 0.617021 (-4925 4850);
PAINT SKYBLUE (-4925 4850);
FORCEPROP 2 LASTPIN (-3275 500) $PN K53
J 0
(-3265 510);
DISPLAY 0.617021 (-3265 510);
PAINT ORANGE (-3265 510);
FORCEPROP 2 LASTPIN (-3275 1550) $PN T47
J 0
(-3265 1560);
DISPLAY 0.617021 (-3265 1560);
PAINT ORANGE (-3265 1560);
FORCEPROP 2 LASTPIN (-3275 1500) $PN M49
J 0
(-3265 1510);
DISPLAY 0.617021 (-3265 1510);
PAINT ORANGE (-3265 1510);
FORCEPROP 2 LASTPIN (-3275 1450) $PN R48
J 0
(-3265 1460);
DISPLAY 0.617021 (-3265 1460);
PAINT ORANGE (-3265 1460);
FORCEPROP 2 LASTPIN (-3275 1400) $PN N50
J 0
(-3265 1410);
DISPLAY 0.617021 (-3265 1410);
PAINT ORANGE (-3265 1410);
FORCEPROP 2 LASTPIN (-3275 2750) $PN N48
J 0
(-3265 2760);
DISPLAY 0.617021 (-3265 2760);
PAINT ORANGE (-3265 2760);
FORCEPROP 2 LASTPIN (-3275 2700) $PN R52
J 0
(-3265 2710);
DISPLAY 0.617021 (-3265 2710);
PAINT ORANGE (-3265 2710);
FORCEPROP 2 LASTPIN (-3275 2650) $PN N52
J 0
(-3265 2660);
DISPLAY 0.617021 (-3265 2660);
PAINT ORANGE (-3265 2660);
FORCEPROP 2 LASTPIN (-3275 2600) $PN T51
J 0
(-3265 2610);
DISPLAY 0.617021 (-3265 2610);
PAINT ORANGE (-3265 2610);
FORCEPROP 2 LASTPIN (-3275 2550) $PN M51
J 0
(-3265 2560);
DISPLAY 0.617021 (-3265 2560);
PAINT ORANGE (-3265 2560);
FORCEPROP 2 LASTPIN (-3275 2500) $PN T61
J 0
(-3265 2510);
DISPLAY 0.617021 (-3265 2510);
PAINT ORANGE (-3265 2510);
FORCEPROP 2 LASTPIN (-3275 2450) $PN R60
J 0
(-3265 2460);
DISPLAY 0.617021 (-3265 2460);
PAINT ORANGE (-3265 2460);
FORCEPROP 2 LASTPIN (-3275 2400) $PN M55
J 0
(-3265 2410);
DISPLAY 0.617021 (-3265 2410);
PAINT ORANGE (-3265 2410);
FORCEPROP 2 LASTPIN (-3275 2350) $PN K59
J 0
(-3265 2360);
DISPLAY 0.617021 (-3265 2360);
PAINT ORANGE (-3265 2360);
FORCEPROP 2 LASTPIN (-3275 2300) $PN W60
J 0
(-3265 2310);
DISPLAY 0.617021 (-3265 2310);
PAINT ORANGE (-3265 2310);
FORCEPROP 2 LASTPIN (-3275 2250) $PN V61
J 0
(-3265 2260);
DISPLAY 0.617021 (-3265 2260);
PAINT ORANGE (-3265 2260);
FORCEPROP 2 LASTPIN (-3275 2200) $PN T59
J 0
(-3265 2210);
DISPLAY 0.617021 (-3265 2210);
PAINT ORANGE (-3265 2210);
FORCEPROP 2 LASTPIN (-3275 2150) $PN R58
J 0
(-3265 2160);
DISPLAY 0.617021 (-3265 2160);
PAINT ORANGE (-3265 2160);
FORCEPROP 2 LASTPIN (-3275 2100) $PN M59
J 0
(-3265 2110);
DISPLAY 0.617021 (-3265 2110);
PAINT ORANGE (-3265 2110);
FORCEPROP 2 LASTPIN (-3275 2050) $PN N58
J 0
(-3265 2060);
DISPLAY 0.617021 (-3265 2060);
PAINT ORANGE (-3265 2060);
FORCEPROP 2 LASTPIN (-3275 2000) $PN K57
J 0
(-3265 2010);
DISPLAY 0.617021 (-3265 2010);
PAINT ORANGE (-3265 2010);
FORCEPROP 2 LASTPIN (-3275 1950) $PN J58
J 0
(-3265 1960);
DISPLAY 0.617021 (-3265 1960);
PAINT ORANGE (-3265 1960);
FORCEPROP 2 LASTPIN (-3275 1900) $PN J52
J 0
(-3265 1910);
DISPLAY 0.617021 (-3265 1910);
PAINT ORANGE (-3265 1910);
FORCEPROP 2 LASTPIN (-4975 1400) $PN M67
J 2
(-4985 1410);
DISPLAY 0.617021 (-4985 1410);
PAINT ORANGE (-4985 1410);
FORCEPROP 2 LASTPIN (-4975 1350) $PN H67
J 2
(-4985 1360);
DISPLAY 0.617021 (-4985 1360);
PAINT ORANGE (-4985 1360);
FORCEPROP 2 LASTPIN (-4975 1300) $PN M69
J 2
(-4985 1310);
DISPLAY 0.617021 (-4985 1310);
PAINT ORANGE (-4985 1310);
FORCEPROP 2 LASTPIN (-4975 1250) $PN L70
J 2
(-4985 1260);
DISPLAY 0.617021 (-4985 1260);
PAINT ORANGE (-4985 1260);
FORCEPROP 2 LASTPIN (-4975 1200) $PN L66
J 2
(-4985 1210);
DISPLAY 0.617021 (-4985 1210);
PAINT ORANGE (-4985 1210);
FORCEPROP 2 LASTPIN (-4975 1150) $PN J66
J 2
(-4985 1160);
DISPLAY 0.617021 (-4985 1160);
PAINT ORANGE (-4985 1160);
FORCEPROP 2 LASTPIN (-4975 1100) $PN H69
J 2
(-4985 1110);
DISPLAY 0.617021 (-4985 1110);
PAINT ORANGE (-4985 1110);
FORCEPROP 2 LASTPIN (-4975 1050) $PN J70
J 2
(-4985 1060);
DISPLAY 0.617021 (-4985 1060);
PAINT ORANGE (-4985 1060);
FORCEPROP 2 LASTPIN (-3275 4650) $PN J68
J 0
(-3265 4660);
DISPLAY 0.617021 (-3265 4660);
PAINT ORANGE (-3265 4660);
FORCEPROP 2 LASTPIN (-3275 4600) $PN V27
J 0
(-3265 4610);
DISPLAY 0.617021 (-3265 4610);
PAINT ORANGE (-3265 4610);
FORCEPROP 2 LASTPIN (-3275 4550) $PN C28
J 0
(-3265 4560);
DISPLAY 0.617021 (-3265 4560);
PAINT ORANGE (-3265 4560);
FORCEPROP 2 LASTPIN (-3275 4500) $PN C34
J 0
(-3265 4510);
DISPLAY 0.617021 (-3265 4510);
PAINT ORANGE (-3265 4510);
FORCEPROP 2 LASTPIN (-3275 4450) $PN L42
J 0
(-3265 4460);
DISPLAY 0.617021 (-3265 4460);
PAINT ORANGE (-3265 4460);
FORCEPROP 2 LASTPIN (-3275 4400) $PN D73
J 0
(-3265 4410);
DISPLAY 0.617021 (-3265 4410);
PAINT ORANGE (-3265 4410);
FORCEPROP 2 LASTPIN (-3275 4350) $PN F79
J 0
(-3265 4360);
DISPLAY 0.617021 (-3265 4360);
PAINT ORANGE (-3265 4360);
FORCEPROP 2 LASTPIN (-3275 4300) $PN AF81
J 0
(-3265 4310);
DISPLAY 0.617021 (-3265 4310);
PAINT ORANGE (-3265 4310);
FORCEPROP 2 LASTPIN (-3275 4250) $PN AT81
J 0
(-3265 4260);
DISPLAY 0.617021 (-3265 4260);
PAINT ORANGE (-3265 4260);
FORCEPROP 2 LASTPIN (-3275 4200) $PN L68
J 0
(-3265 4210);
DISPLAY 0.617021 (-3265 4210);
PAINT ORANGE (-3265 4210);
FORCEPROP 2 LASTPIN (-3275 4150) $PN Y27
J 0
(-3265 4160);
DISPLAY 0.617021 (-3265 4160);
PAINT ORANGE (-3265 4160);
FORCEPROP 2 LASTPIN (-3275 4100) $PN E28
J 0
(-3265 4110);
DISPLAY 0.617021 (-3265 4110);
PAINT ORANGE (-3265 4110);
FORCEPROP 2 LASTPIN (-3275 4050) $PN E34
J 0
(-3265 4060);
DISPLAY 0.617021 (-3265 4060);
PAINT ORANGE (-3265 4060);
FORCEPROP 2 LASTPIN (-3275 4000) $PN R42
J 0
(-3265 4010);
DISPLAY 0.617021 (-3265 4010);
PAINT ORANGE (-3265 4010);
FORCEPROP 2 LASTPIN (-3275 3950) $PN F73
J 0
(-3265 3960);
DISPLAY 0.617021 (-3265 3960);
PAINT ORANGE (-3265 3960);
FORCEPROP 2 LASTPIN (-3275 3900) $PN H79
J 0
(-3265 3910);
DISPLAY 0.617021 (-3265 3910);
PAINT ORANGE (-3265 3910);
FORCEPROP 2 LASTPIN (-3275 3850) $PN AE80
J 0
(-3265 3860);
DISPLAY 0.617021 (-3265 3860);
PAINT ORANGE (-3265 3860);
FORCEPROP 2 LASTPIN (-3275 3800) $PN AR80
J 0
(-3265 3810);
DISPLAY 0.617021 (-3265 3810);
PAINT ORANGE (-3265 3810);
FORCEPROP 2 LASTPIN (-3275 3700) $PN G68
J 0
(-3265 3710);
DISPLAY 0.617021 (-3265 3710);
PAINT ORANGE (-3265 3710);
FORCEPROP 2 LASTPIN (-3275 3650) $PN T27
J 0
(-3265 3660);
DISPLAY 0.617021 (-3265 3660);
PAINT ORANGE (-3265 3660);
FORCEPROP 2 LASTPIN (-3275 3600) $PN A28
J 0
(-3265 3610);
DISPLAY 0.617021 (-3265 3610);
PAINT ORANGE (-3265 3610);
FORCEPROP 2 LASTPIN (-3275 3550) $PN A34
J 0
(-3265 3560);
DISPLAY 0.617021 (-3265 3560);
PAINT ORANGE (-3265 3560);
FORCEPROP 2 LASTPIN (-3275 3500) $PN J42
J 0
(-3265 3510);
DISPLAY 0.617021 (-3265 3510);
PAINT ORANGE (-3265 3510);
FORCEPROP 2 LASTPIN (-3275 3450) $PN B73
J 0
(-3265 3460);
DISPLAY 0.617021 (-3265 3460);
PAINT ORANGE (-3265 3460);
FORCEPROP 2 LASTPIN (-3275 3400) $PN D79
J 0
(-3265 3410);
DISPLAY 0.617021 (-3265 3410);
PAINT ORANGE (-3265 3410);
FORCEPROP 2 LASTPIN (-3275 3350) $PN AG82
J 0
(-3265 3360);
DISPLAY 0.617021 (-3265 3360);
PAINT ORANGE (-3265 3360);
FORCEPROP 2 LASTPIN (-3275 3300) $PN AU82
J 0
(-3265 3310);
DISPLAY 0.617021 (-3265 3310);
PAINT ORANGE (-3265 3310);
FORCEPROP 2 LASTPIN (-3275 3250) $PN N68
J 0
(-3265 3260);
DISPLAY 0.617021 (-3265 3260);
PAINT ORANGE (-3265 3260);
FORCEPROP 2 LASTPIN (-3275 3200) $PN AB27
J 0
(-3265 3210);
DISPLAY 0.617021 (-3265 3210);
PAINT ORANGE (-3265 3210);
FORCEPROP 2 LASTPIN (-3275 3150) $PN G28
J 0
(-3265 3160);
DISPLAY 0.617021 (-3265 3160);
PAINT ORANGE (-3265 3160);
FORCEPROP 2 LASTPIN (-3275 3100) $PN G34
J 0
(-3265 3110);
DISPLAY 0.617021 (-3265 3110);
PAINT ORANGE (-3265 3110);
FORCEPROP 2 LASTPIN (-3275 3050) $PN N42
J 0
(-3265 3060);
DISPLAY 0.617021 (-3265 3060);
PAINT ORANGE (-3265 3060);
FORCEPROP 2 LASTPIN (-3275 3000) $PN H73
J 0
(-3265 3010);
DISPLAY 0.617021 (-3265 3010);
PAINT ORANGE (-3265 3010);
FORCEPROP 2 LASTPIN (-3275 2950) $PN K79
J 0
(-3265 2960);
DISPLAY 0.617021 (-3265 2960);
PAINT ORANGE (-3265 2960);
FORCEPROP 2 LASTPIN (-3275 2900) $PN AD79
J 0
(-3265 2910);
DISPLAY 0.617021 (-3265 2910);
PAINT ORANGE (-3265 2910);
FORCEPROP 2 LASTPIN (-3275 2850) $PN AP79
J 0
(-3265 2860);
DISPLAY 0.617021 (-3265 2860);
PAINT ORANGE (-3265 2860);
FORCEPROP 2 LASTPIN (-4975 4650) $PN AA26
J 2
(-4985 4660);
DISPLAY 0.617021 (-4985 4660);
PAINT ORANGE (-4985 4660);
FORCEPROP 2 LASTPIN (-4975 4600) $PN U26
J 2
(-4985 4610);
DISPLAY 0.617021 (-4985 4610);
PAINT ORANGE (-4985 4610);
FORCEPROP 2 LASTPIN (-4975 4550) $PN Y29
J 2
(-4985 4560);
DISPLAY 0.617021 (-4985 4560);
PAINT ORANGE (-4985 4560);
FORCEPROP 2 LASTPIN (-4975 4500) $PN V29
J 2
(-4985 4510);
DISPLAY 0.617021 (-4985 4510);
PAINT ORANGE (-4985 4510);
FORCEPROP 2 LASTPIN (-4975 4450) $PN Y25
J 2
(-4985 4460);
DISPLAY 0.617021 (-4985 4460);
PAINT ORANGE (-4985 4460);
FORCEPROP 2 LASTPIN (-4975 4400) $PN V25
J 2
(-4985 4410);
DISPLAY 0.617021 (-4985 4410);
PAINT ORANGE (-4985 4410);
FORCEPROP 2 LASTPIN (-4975 4350) $PN AA28
J 2
(-4985 4360);
DISPLAY 0.617021 (-4985 4360);
PAINT ORANGE (-4985 4360);
FORCEPROP 2 LASTPIN (-4975 4300) $PN U28
J 2
(-4985 4310);
DISPLAY 0.617021 (-4985 4310);
PAINT ORANGE (-4985 4310);
FORCEPROP 2 LASTPIN (-4975 4250) $PN F27
J 2
(-4985 4260);
DISPLAY 0.617021 (-4985 4260);
PAINT ORANGE (-4985 4260);
FORCEPROP 2 LASTPIN (-4975 4200) $PN B27
J 2
(-4985 4210);
DISPLAY 0.617021 (-4985 4210);
PAINT ORANGE (-4985 4210);
FORCEPROP 2 LASTPIN (-4975 4150) $PN F29
J 2
(-4985 4160);
DISPLAY 0.617021 (-4985 4160);
PAINT ORANGE (-4985 4160);
FORCEPROP 2 LASTPIN (-4975 4100) $PN E30
J 2
(-4985 4110);
DISPLAY 0.617021 (-4985 4110);
PAINT ORANGE (-4985 4110);
FORCEPROP 2 LASTPIN (-4975 4050) $PN E26
J 2
(-4985 4060);
DISPLAY 0.617021 (-4985 4060);
PAINT ORANGE (-4985 4060);
FORCEPROP 2 LASTPIN (-4975 4000) $PN C26
J 2
(-4985 4010);
DISPLAY 0.617021 (-4985 4010);
PAINT ORANGE (-4985 4010);
FORCEPROP 2 LASTPIN (-4975 3950) $PN B29
J 2
(-4985 3960);
DISPLAY 0.617021 (-4985 3960);
PAINT ORANGE (-4985 3960);
FORCEPROP 2 LASTPIN (-4975 3900) $PN C30
J 2
(-4985 3910);
DISPLAY 0.617021 (-4985 3910);
PAINT ORANGE (-4985 3910);
FORCEPROP 2 LASTPIN (-4975 3850) $PN F33
J 2
(-4985 3860);
DISPLAY 0.617021 (-4985 3860);
PAINT ORANGE (-4985 3860);
FORCEPROP 2 LASTPIN (-4975 3800) $PN B33
J 2
(-4985 3810);
DISPLAY 0.617021 (-4985 3810);
PAINT ORANGE (-4985 3810);
FORCEPROP 2 LASTPIN (-4975 3750) $PN F35
J 2
(-4985 3760);
DISPLAY 0.617021 (-4985 3760);
PAINT ORANGE (-4985 3760);
FORCEPROP 2 LASTPIN (-4975 3700) $PN E36
J 2
(-4985 3710);
DISPLAY 0.617021 (-4985 3710);
PAINT ORANGE (-4985 3710);
FORCEPROP 2 LASTPIN (-4975 3650) $PN E32
J 2
(-4985 3660);
DISPLAY 0.617021 (-4985 3660);
PAINT ORANGE (-4985 3660);
FORCEPROP 2 LASTPIN (-4975 3600) $PN C32
J 2
(-4985 3610);
DISPLAY 0.617021 (-4985 3610);
PAINT ORANGE (-4985 3610);
FORCEPROP 2 LASTPIN (-4975 3550) $PN B35
J 2
(-4985 3560);
DISPLAY 0.617021 (-4985 3560);
PAINT ORANGE (-4985 3560);
FORCEPROP 2 LASTPIN (-4975 3500) $PN C36
J 2
(-4985 3510);
DISPLAY 0.617021 (-4985 3510);
PAINT ORANGE (-4985 3510);
FORCEPROP 2 LASTPIN (-4975 3450) $PN P41
J 2
(-4985 3460);
DISPLAY 0.617021 (-4985 3460);
PAINT ORANGE (-4985 3460);
FORCEPROP 2 LASTPIN (-4975 3400) $PN K41
J 2
(-4985 3410);
DISPLAY 0.617021 (-4985 3410);
PAINT ORANGE (-4985 3410);
FORCEPROP 2 LASTPIN (-4975 3350) $PN T43
J 2
(-4985 3360);
DISPLAY 0.617021 (-4985 3360);
PAINT ORANGE (-4985 3360);
FORCEPROP 2 LASTPIN (-4975 3300) $PN P43
J 2
(-4985 3310);
DISPLAY 0.617021 (-4985 3310);
PAINT ORANGE (-4985 3310);
FORCEPROP 2 LASTPIN (-4975 3250) $PN N40
J 2
(-4985 3260);
DISPLAY 0.617021 (-4985 3260);
PAINT ORANGE (-4985 3260);
FORCEPROP 2 LASTPIN (-4975 3200) $PN L40
J 2
(-4985 3210);
DISPLAY 0.617021 (-4985 3210);
PAINT ORANGE (-4985 3210);
FORCEPROP 2 LASTPIN (-4975 3150) $PN H43
J 2
(-4985 3160);
DISPLAY 0.617021 (-4985 3160);
PAINT ORANGE (-4985 3160);
FORCEPROP 2 LASTPIN (-4975 3100) $PN K43
J 2
(-4985 3110);
DISPLAY 0.617021 (-4985 3110);
PAINT ORANGE (-4985 3110);
FORCEPROP 2 LASTPIN (-4975 3050) $PN G72
J 2
(-4985 3060);
DISPLAY 0.617021 (-4985 3060);
PAINT ORANGE (-4985 3060);
FORCEPROP 2 LASTPIN (-4975 3000) $PN C72
J 2
(-4985 3010);
DISPLAY 0.617021 (-4985 3010);
PAINT ORANGE (-4985 3010);
FORCEPROP 2 LASTPIN (-4975 2950) $PN G74
J 2
(-4985 2960);
DISPLAY 0.617021 (-4985 2960);
PAINT ORANGE (-4985 2960);
FORCEPROP 2 LASTPIN (-4975 2900) $PN F75
J 2
(-4985 2910);
DISPLAY 0.617021 (-4985 2910);
PAINT ORANGE (-4985 2910);
FORCEPROP 2 LASTPIN (-4975 2850) $PN F71
J 2
(-4985 2860);
DISPLAY 0.617021 (-4985 2860);
PAINT ORANGE (-4985 2860);
FORCEPROP 2 LASTPIN (-4975 2800) $PN D71
J 2
(-4985 2810);
DISPLAY 0.617021 (-4985 2810);
PAINT ORANGE (-4985 2810);
FORCEPROP 2 LASTPIN (-4975 2750) $PN C74
J 2
(-4985 2760);
DISPLAY 0.617021 (-4985 2760);
PAINT ORANGE (-4985 2760);
FORCEPROP 2 LASTPIN (-4975 2700) $PN D75
J 2
(-4985 2710);
DISPLAY 0.617021 (-4985 2710);
PAINT ORANGE (-4985 2710);
FORCEPROP 2 LASTPIN (-4975 2650) $PN J78
J 2
(-4985 2660);
DISPLAY 0.617021 (-4985 2660);
PAINT ORANGE (-4985 2660);
FORCEPROP 2 LASTPIN (-4975 2600) $PN E78
J 2
(-4985 2610);
DISPLAY 0.617021 (-4985 2610);
PAINT ORANGE (-4985 2610);
FORCEPROP 2 LASTPIN (-4975 2550) $PN H81
J 2
(-4985 2560);
DISPLAY 0.617021 (-4985 2560);
PAINT ORANGE (-4985 2560);
FORCEPROP 2 LASTPIN (-4975 2500) $PN F81
J 2
(-4985 2510);
DISPLAY 0.617021 (-4985 2510);
PAINT ORANGE (-4985 2510);
FORCEPROP 2 LASTPIN (-4975 2450) $PN H77
J 2
(-4985 2460);
DISPLAY 0.617021 (-4985 2460);
PAINT ORANGE (-4985 2460);
FORCEPROP 2 LASTPIN (-4975 2400) $PN F77
J 2
(-4985 2410);
DISPLAY 0.617021 (-4985 2410);
PAINT ORANGE (-4985 2410);
FORCEPROP 2 LASTPIN (-4975 2350) $PN J80
J 2
(-4985 2360);
DISPLAY 0.617021 (-4985 2360);
PAINT ORANGE (-4985 2360);
FORCEPROP 2 LASTPIN (-4975 2300) $PN E80
J 2
(-4985 2310);
DISPLAY 0.617021 (-4985 2310);
PAINT ORANGE (-4985 2310);
FORCEPROP 2 LASTPIN (-4975 2250) $PN AC80
J 2
(-4985 2260);
DISPLAY 0.617021 (-4985 2260);
PAINT ORANGE (-4985 2260);
FORCEPROP 2 LASTPIN (-4975 2200) $PN AE82
J 2
(-4985 2210);
DISPLAY 0.617021 (-4985 2210);
PAINT ORANGE (-4985 2210);
FORCEPROP 2 LASTPIN (-4975 2150) $PN AH79
J 2
(-4985 2160);
DISPLAY 0.617021 (-4985 2160);
PAINT ORANGE (-4985 2160);
FORCEPROP 2 LASTPIN (-4975 2100) $PN AJ80
J 2
(-4985 2110);
DISPLAY 0.617021 (-4985 2110);
PAINT ORANGE (-4985 2110);
FORCEPROP 2 LASTPIN (-4975 2050) $PN AB81
J 2
(-4985 2060);
DISPLAY 0.617021 (-4985 2060);
PAINT ORANGE (-4985 2060);
FORCEPROP 2 LASTPIN (-4975 2000) $PN AC82
J 2
(-4985 2010);
DISPLAY 0.617021 (-4985 2010);
PAINT ORANGE (-4985 2010);
FORCEPROP 2 LASTPIN (-4975 1950) $PN AF79
J 2
(-4985 1960);
DISPLAY 0.617021 (-4985 1960);
PAINT ORANGE (-4985 1960);
FORCEPROP 2 LASTPIN (-4975 1900) $PN AH81
J 2
(-4985 1910);
DISPLAY 0.617021 (-4985 1910);
PAINT ORANGE (-4985 1910);
FORCEPROP 2 LASTPIN (-4975 1850) $PN AN80
J 2
(-4985 1860);
DISPLAY 0.617021 (-4985 1860);
PAINT ORANGE (-4985 1860);
FORCEPROP 2 LASTPIN (-4975 1800) $PN AR82
J 2
(-4985 1810);
DISPLAY 0.617021 (-4985 1810);
PAINT ORANGE (-4985 1810);
FORCEPROP 2 LASTPIN (-4975 1750) $PN AV79
J 2
(-4985 1760);
DISPLAY 0.617021 (-4985 1760);
PAINT ORANGE (-4985 1760);
FORCEPROP 2 LASTPIN (-4975 1700) $PN AW80
J 2
(-4985 1710);
DISPLAY 0.617021 (-4985 1710);
PAINT ORANGE (-4985 1710);
FORCEPROP 2 LASTPIN (-4975 1650) $PN AM81
J 2
(-4985 1660);
DISPLAY 0.617021 (-4985 1660);
PAINT ORANGE (-4985 1660);
FORCEPROP 2 LASTPIN (-4975 1600) $PN AN82
J 2
(-4985 1610);
DISPLAY 0.617021 (-4985 1610);
PAINT ORANGE (-4985 1610);
FORCEPROP 2 LASTPIN (-4975 1550) $PN AT79
J 2
(-4985 1560);
DISPLAY 0.617021 (-4985 1560);
PAINT ORANGE (-4985 1560);
FORCEPROP 2 LASTPIN (-4975 1500) $PN AV81
J 2
(-4985 1510);
DISPLAY 0.617021 (-4985 1510);
PAINT ORANGE (-4985 1510);
FORCEPROP 2 LASTPIN (-3275 1300) $PN R46
J 0
(-3265 1310);
DISPLAY 0.617021 (-3265 1310);
PAINT ORANGE (-3265 1310);
FORCEPROP 2 LASTPIN (-3275 1250) $PN M45
J 0
(-3265 1260);
DISPLAY 0.617021 (-3265 1260);
PAINT ORANGE (-3265 1260);
FORCEPROP 2 LASTPIN (-3275 1200) $PN T49
J 0
(-3265 1210);
DISPLAY 0.617021 (-3265 1210);
PAINT ORANGE (-3265 1210);
FORCEPROP 2 LASTPIN (-3275 1150) $PN J50
J 0
(-3265 1160);
DISPLAY 0.617021 (-3265 1160);
PAINT ORANGE (-3265 1160);
FORCEPROP 2 LASTPIN (-3275 1100) $PN V47
J 0
(-3265 1110);
DISPLAY 0.617021 (-3265 1110);
PAINT ORANGE (-3265 1110);
FORCEPROP 2 LASTPIN (-3275 1050) $PN N46
J 0
(-3265 1060);
DISPLAY 0.617021 (-3265 1060);
PAINT ORANGE (-3265 1060);
FORCEPROP 2 LASTPIN (-3275 1000) $PN R50
J 0
(-3265 1010);
DISPLAY 0.617021 (-3265 1010);
PAINT ORANGE (-3265 1010);
FORCEPROP 2 LASTPIN (-3275 950) $PN K51
J 0
(-3265 960);
DISPLAY 0.617021 (-3265 960);
PAINT ORANGE (-3265 960);
FORCEPROP 2 LASTPIN (-4975 950) $PN T57
J 2
(-4985 960);
DISPLAY 0.617021 (-4985 960);
PAINT ORANGE (-4985 960);
FORCEPROP 2 LASTPIN (-4975 900) $PN M57
J 2
(-4985 910);
DISPLAY 0.617021 (-4985 910);
PAINT ORANGE (-4985 910);
FORCEPROP 2 LASTPIN (-4975 850) $PN T55
J 2
(-4985 860);
DISPLAY 0.617021 (-4985 860);
PAINT ORANGE (-4985 860);
FORCEPROP 2 LASTPIN (-4975 800) $PN N54
J 2
(-4985 810);
DISPLAY 0.617021 (-4985 810);
PAINT ORANGE (-4985 810);
FORCEPROP 2 LASTPIN (-4975 750) $PN R56
J 2
(-4985 760);
DISPLAY 0.617021 (-4985 760);
PAINT ORANGE (-4985 760);
FORCEPROP 2 LASTPIN (-4975 700) $PN N56
J 2
(-4985 710);
DISPLAY 0.617021 (-4985 710);
PAINT ORANGE (-4985 710);
FORCEPROP 2 LASTPIN (-4975 650) $PN R54
J 2
(-4985 660);
DISPLAY 0.617021 (-4985 660);
PAINT ORANGE (-4985 660);
FORCEPROP 2 LASTPIN (-4975 600) $PN M53
J 2
(-4985 610);
DISPLAY 0.617021 (-4985 610);
PAINT ORANGE (-4985 610);
FORCEPROP 2 LASTPIN (-3275 1800) $PN L64
J 0
(-3265 1810);
DISPLAY 0.617021 (-3265 1810);
PAINT ORANGE (-3265 1810);
FORCEPROP 2 LASTPIN (-3275 1750) $PN K63
J 0
(-3265 1760);
DISPLAY 0.617021 (-3265 1760);
PAINT ORANGE (-3265 1760);
FORCEPROP 2 LASTPIN (-3275 1700) $PN R64
J 0
(-3265 1710);
DISPLAY 0.617021 (-3265 1710);
PAINT ORANGE (-3265 1710);
FORCEPROP 2 LASTPIN (-3275 1650) $PN N62
J 0
(-3265 1660);
DISPLAY 0.617021 (-3265 1660);
PAINT ORANGE (-3265 1660);
FORCEPROP 2 LASTPIN (-4975 500) $PN M47
J 2
(-4985 510);
DISPLAY 0.617021 (-4985 510);
PAINT ORANGE (-4985 510);
FORCEPROP 2 LASTPIN (-3275 850) $PN N60
J 0
(-3265 860);
DISPLAY 0.617021 (-3265 860);
PAINT ORANGE (-3265 860);
FORCEPROP 2 LASTPIN (-3275 800) $PN M61
J 0
(-3265 810);
DISPLAY 0.617021 (-3265 810);
PAINT ORANGE (-3265 810);
FORCEPROP 2 LASTPIN (-3275 750) $PN K55
J 0
(-3265 760);
DISPLAY 0.617021 (-3265 760);
PAINT ORANGE (-3265 760);
FORCEPROP 2 LASTPIN (-3275 700) $PN T53
J 0
(-3265 710);
DISPLAY 0.617021 (-3265 710);
PAINT ORANGE (-3265 710);
FORCEPROP 2 LASTPIN (-3275 550) $PN W62
J 0
(-3265 560);
DISPLAY 0.617021 (-3265 560);
PAINT ORANGE (-3265 560);
FORCEPROP 2 LASTPIN (-3275 600) $PN T63
J 0
(-3265 610);
DISPLAY 0.617021 (-3265 610);
PAINT ORANGE (-3265 610);
FORCEPROP 1 LAST PACK_TYPE BGA1
J 0
(-4925 4950);
PAINT SKYBLUE (-4925 4950);
DISPLAY INVISIBLE (-4925 4950);
FORCEPROP 2 LAST SEC_TYPE BGA1
J 0
(-4925 4950);
DISPLAY 1.021277 (-4925 4950);
PAINT ORANGE (-4925 4950);
DISPLAY INVISIBLE (-4925 4950);
FORCEPROP 2 LAST CDS_LIB chpset_lib
J 0
(-4125 2550);
PAINT ORANGE (-4125 2550);
DISPLAY INVISIBLE (-4125 2550);
FORCEPROP 2 LAST SEC 4
J 0
(-4925 4950);
DISPLAY 0.680851 (-4925 4950);
PAINT MONO (-4925 4950);
DISPLAY INVISIBLE (-4925 4950);
FORCEPROP 2 LAST CDS_LOCATION U5D1
J 0
(-4925 4900);
DISPLAY 0.617021 (-4925 4900);
PAINT AQUA (-4925 4900);
DISPLAY INVISIBLE (-4925 4900);
FORCEPROP 1 LAST PATH I172
J 0
(-4125 4850);
PAINT GREEN (-4125 4850);
DISPLAY INVISIBLE (-4125 4850);
FORCEPROP 0 LAST ROOM CPU0
J 0
(-4925 5000);
DISPLAY 1.021277 (-4925 5000);
PAINT ORANGE (-4925 5000);
DISPLAY INVISIBLE (-4925 5000);
FORCEADD TAP..6
(-5525 1300);
FORCEPROP 3 LASTPIN (-5475 1300) SIG_NAME M_B_ECC<5>
J 0
(-5465 1310);
DISPLAY 0.659574 (-5465 1310);
PAINT MONO (-5465 1310);
DISPLAY INVISIBLE (-5465 1310);
FORCEPROP 1 LASTPIN (-5475 1300) BN 5
J 0
(-5527 1308);
DISPLAY 0.617021 (-5527 1308);
PAINT PINK (-5527 1308);
FORCEPROP 2 LAST CDS_LIB mstr_standard
J 0
(-5525 1300);
PAINT MONO (-5525 1300);
DISPLAY INVISIBLE (-5525 1300);
FORCEPROP 1 LAST BODY_TYPE PLUMBING
J 0
(-5525 1250);
DISPLAY 1.595745 (-5525 1250);
PAINT GREEN (-5525 1250);
DISPLAY INVISIBLE (-5525 1250);
FORCEPROP 1 LAST HDL_TAP TRUE
J 0
(-5200 1175);
DISPLAY 1.595745 (-5200 1175);
PAINT GREEN (-5200 1175);
DISPLAY INVISIBLE (-5200 1175);
FORCEPROP 1 LAST PATH I18
J 0
(-5527 1300);
DISPLAY 0.872340 (-5527 1300);
PAINT GREEN (-5527 1300);
DISPLAY INVISIBLE (-5527 1300);
FORCEADD TAP..6
(-5525 1350);
FORCEPROP 3 LASTPIN (-5475 1350) SIG_NAME M_B_ECC<6>
J 0
(-5465 1360);
DISPLAY 0.659574 (-5465 1360);
PAINT MONO (-5465 1360);
DISPLAY INVISIBLE (-5465 1360);
FORCEPROP 1 LASTPIN (-5475 1350) BN 6
J 0
(-5527 1358);
DISPLAY 0.617021 (-5527 1358);
PAINT PINK (-5527 1358);
FORCEPROP 2 LAST CDS_LIB mstr_standard
J 0
(-5525 1350);
PAINT MONO (-5525 1350);
DISPLAY INVISIBLE (-5525 1350);
FORCEPROP 1 LAST BODY_TYPE PLUMBING
J 0
(-5525 1300);
DISPLAY 1.595745 (-5525 1300);
PAINT GREEN (-5525 1300);
DISPLAY INVISIBLE (-5525 1300);
FORCEPROP 1 LAST HDL_TAP TRUE
J 0
(-5200 1225);
DISPLAY 1.595745 (-5200 1225);
PAINT GREEN (-5200 1225);
DISPLAY INVISIBLE (-5200 1225);
FORCEPROP 1 LAST PATH I19
J 0
(-5527 1350);
DISPLAY 0.872340 (-5527 1350);
PAINT GREEN (-5527 1350);
DISPLAY INVISIBLE (-5527 1350);
FORCEADD OFFPAGE..5
(-6375 800);
FORCEPROP 2 LAST $XR0 45 
J 0
(-6629 800);
DISPLAY 0.638298 (-6629 800);
PAINT MONO (-6629 800);
FORCEPROP 2 LAST $XR1 46 
J 0
(-6719 800);
DISPLAY 0.638298 (-6719 800);
PAINT MONO (-6719 800);
FORCEPROP 2 LAST CDS_LIB mstr_standard
J 0
(-6375 800);
PAINT MONO (-6375 800);
DISPLAY INVISIBLE (-6375 800);
FORCEPROP 1 LAST OFFPAGE TRUE
J 0
(-6050 675);
DISPLAY 1.170213 (-6050 675);
PAINT GREEN (-6050 675);
DISPLAY INVISIBLE (-6050 675);
FORCEPROP 1 LAST COMMENT_BODY TRUE
J 0
(-6275 725);
DISPLAY 1.170213 (-6275 725);
PAINT GREEN (-6275 725);
DISPLAY INVISIBLE (-6275 725);
FORCEPROP 2 LAST PATH I2
J 0
(-6325 875);
DISPLAY 1.021277 (-6325 875);
PAINT ORANGE (-6325 875);
DISPLAY INVISIBLE (-6325 875);
FORCEADD TAP..6
(-5525 1400);
FORCEPROP 3 LASTPIN (-5475 1400) SIG_NAME M_B_ECC<7>
J 0
(-5465 1410);
DISPLAY 0.659574 (-5465 1410);
PAINT MONO (-5465 1410);
DISPLAY INVISIBLE (-5465 1410);
FORCEPROP 1 LASTPIN (-5475 1400) BN 7
J 0
(-5527 1408);
DISPLAY 0.617021 (-5527 1408);
PAINT PINK (-5527 1408);
FORCEPROP 2 LAST CDS_LIB mstr_standard
J 0
(-5525 1400);
PAINT MONO (-5525 1400);
DISPLAY INVISIBLE (-5525 1400);
FORCEPROP 1 LAST BODY_TYPE PLUMBING
J 0
(-5525 1350);
DISPLAY 1.595745 (-5525 1350);
PAINT GREEN (-5525 1350);
DISPLAY INVISIBLE (-5525 1350);
FORCEPROP 1 LAST HDL_TAP TRUE
J 0
(-5200 1275);
DISPLAY 1.595745 (-5200 1275);
PAINT GREEN (-5200 1275);
DISPLAY INVISIBLE (-5200 1275);
FORCEPROP 1 LAST PATH I20
J 0
(-5527 1400);
DISPLAY 0.872340 (-5527 1400);
PAINT GREEN (-5527 1400);
DISPLAY INVISIBLE (-5527 1400);
FORCEADD TAP..6
(-5525 1500);
FORCEPROP 3 LASTPIN (-5475 1500) SIG_NAME M_B_DQ<0>
J 0
(-5465 1510);
DISPLAY 0.659574 (-5465 1510);
PAINT MONO (-5465 1510);
DISPLAY INVISIBLE (-5465 1510);
FORCEPROP 1 LASTPIN (-5475 1500) BN 0
J 0
(-5527 1508);
DISPLAY 0.617021 (-5527 1508);
PAINT PINK (-5527 1508);
FORCEPROP 2 LAST CDS_LIB mstr_standard
J 0
(-5525 1500);
PAINT MONO (-5525 1500);
DISPLAY INVISIBLE (-5525 1500);
FORCEPROP 1 LAST BODY_TYPE PLUMBING
J 0
(-5525 1450);
DISPLAY 1.595745 (-5525 1450);
PAINT GREEN (-5525 1450);
DISPLAY INVISIBLE (-5525 1450);
FORCEPROP 1 LAST HDL_TAP TRUE
J 0
(-5200 1375);
DISPLAY 1.595745 (-5200 1375);
PAINT GREEN (-5200 1375);
DISPLAY INVISIBLE (-5200 1375);
FORCEPROP 1 LAST PATH I21
J 0
(-5527 1500);
DISPLAY 0.872340 (-5527 1500);
PAINT GREEN (-5527 1500);
DISPLAY INVISIBLE (-5527 1500);
FORCEADD TAP..6
(-5525 1550);
FORCEPROP 3 LASTPIN (-5475 1550) SIG_NAME M_B_DQ<1>
J 0
(-5465 1560);
DISPLAY 0.659574 (-5465 1560);
PAINT MONO (-5465 1560);
DISPLAY INVISIBLE (-5465 1560);
FORCEPROP 1 LASTPIN (-5475 1550) BN 1
J 0
(-5527 1558);
DISPLAY 0.617021 (-5527 1558);
PAINT PINK (-5527 1558);
FORCEPROP 2 LAST CDS_LIB mstr_standard
J 0
(-5525 1550);
PAINT MONO (-5525 1550);
DISPLAY INVISIBLE (-5525 1550);
FORCEPROP 1 LAST BODY_TYPE PLUMBING
J 0
(-5525 1500);
DISPLAY 1.595745 (-5525 1500);
PAINT GREEN (-5525 1500);
DISPLAY INVISIBLE (-5525 1500);
FORCEPROP 1 LAST HDL_TAP TRUE
J 0
(-5200 1425);
DISPLAY 1.595745 (-5200 1425);
PAINT GREEN (-5200 1425);
DISPLAY INVISIBLE (-5200 1425);
FORCEPROP 1 LAST PATH I22
J 0
(-5527 1550);
DISPLAY 0.872340 (-5527 1550);
PAINT GREEN (-5527 1550);
DISPLAY INVISIBLE (-5527 1550);
FORCEADD TAP..6
(-5525 1600);
FORCEPROP 3 LASTPIN (-5475 1600) SIG_NAME M_B_DQ<2>
J 0
(-5465 1610);
DISPLAY 0.659574 (-5465 1610);
PAINT MONO (-5465 1610);
DISPLAY INVISIBLE (-5465 1610);
FORCEPROP 1 LASTPIN (-5475 1600) BN 2
J 0
(-5527 1608);
DISPLAY 0.617021 (-5527 1608);
PAINT PINK (-5527 1608);
FORCEPROP 2 LAST CDS_LIB mstr_standard
J 0
(-5525 1600);
PAINT MONO (-5525 1600);
DISPLAY INVISIBLE (-5525 1600);
FORCEPROP 1 LAST BODY_TYPE PLUMBING
J 0
(-5525 1550);
DISPLAY 1.595745 (-5525 1550);
PAINT GREEN (-5525 1550);
DISPLAY INVISIBLE (-5525 1550);
FORCEPROP 1 LAST HDL_TAP TRUE
J 0
(-5200 1475);
DISPLAY 1.595745 (-5200 1475);
PAINT GREEN (-5200 1475);
DISPLAY INVISIBLE (-5200 1475);
FORCEPROP 1 LAST PATH I23
J 0
(-5527 1600);
DISPLAY 0.872340 (-5527 1600);
PAINT GREEN (-5527 1600);
DISPLAY INVISIBLE (-5527 1600);
FORCEADD TAP..6
(-5525 1650);
FORCEPROP 3 LASTPIN (-5475 1650) SIG_NAME M_B_DQ<3>
J 0
(-5465 1660);
DISPLAY 0.659574 (-5465 1660);
PAINT MONO (-5465 1660);
DISPLAY INVISIBLE (-5465 1660);
FORCEPROP 1 LASTPIN (-5475 1650) BN 3
J 0
(-5527 1658);
DISPLAY 0.617021 (-5527 1658);
PAINT PINK (-5527 1658);
FORCEPROP 2 LAST CDS_LIB mstr_standard
J 0
(-5525 1650);
PAINT MONO (-5525 1650);
DISPLAY INVISIBLE (-5525 1650);
FORCEPROP 1 LAST BODY_TYPE PLUMBING
J 0
(-5525 1600);
DISPLAY 1.595745 (-5525 1600);
PAINT GREEN (-5525 1600);
DISPLAY INVISIBLE (-5525 1600);
FORCEPROP 1 LAST HDL_TAP TRUE
J 0
(-5200 1525);
DISPLAY 1.595745 (-5200 1525);
PAINT GREEN (-5200 1525);
DISPLAY INVISIBLE (-5200 1525);
FORCEPROP 1 LAST PATH I24
J 0
(-5527 1650);
DISPLAY 0.872340 (-5527 1650);
PAINT GREEN (-5527 1650);
DISPLAY INVISIBLE (-5527 1650);
FORCEADD TAP..6
(-5525 1700);
FORCEPROP 3 LASTPIN (-5475 1700) SIG_NAME M_B_DQ<4>
J 0
(-5465 1710);
DISPLAY 0.659574 (-5465 1710);
PAINT MONO (-5465 1710);
DISPLAY INVISIBLE (-5465 1710);
FORCEPROP 1 LASTPIN (-5475 1700) BN 4
J 0
(-5527 1708);
DISPLAY 0.617021 (-5527 1708);
PAINT PINK (-5527 1708);
FORCEPROP 2 LAST CDS_LIB mstr_standard
J 0
(-5525 1700);
PAINT MONO (-5525 1700);
DISPLAY INVISIBLE (-5525 1700);
FORCEPROP 1 LAST BODY_TYPE PLUMBING
J 0
(-5525 1650);
DISPLAY 1.595745 (-5525 1650);
PAINT GREEN (-5525 1650);
DISPLAY INVISIBLE (-5525 1650);
FORCEPROP 1 LAST HDL_TAP TRUE
J 0
(-5200 1575);
DISPLAY 1.595745 (-5200 1575);
PAINT GREEN (-5200 1575);
DISPLAY INVISIBLE (-5200 1575);
FORCEPROP 1 LAST PATH I25
J 0
(-5527 1700);
DISPLAY 0.872340 (-5527 1700);
PAINT GREEN (-5527 1700);
DISPLAY INVISIBLE (-5527 1700);
FORCEADD TAP..6
(-5525 1750);
FORCEPROP 3 LASTPIN (-5475 1750) SIG_NAME M_B_DQ<5>
J 0
(-5465 1760);
DISPLAY 0.659574 (-5465 1760);
PAINT MONO (-5465 1760);
DISPLAY INVISIBLE (-5465 1760);
FORCEPROP 1 LASTPIN (-5475 1750) BN 5
J 0
(-5527 1758);
DISPLAY 0.617021 (-5527 1758);
PAINT PINK (-5527 1758);
FORCEPROP 2 LAST CDS_LIB mstr_standard
J 0
(-5525 1750);
PAINT MONO (-5525 1750);
DISPLAY INVISIBLE (-5525 1750);
FORCEPROP 1 LAST BODY_TYPE PLUMBING
J 0
(-5525 1700);
DISPLAY 1.595745 (-5525 1700);
PAINT GREEN (-5525 1700);
DISPLAY INVISIBLE (-5525 1700);
FORCEPROP 1 LAST HDL_TAP TRUE
J 0
(-5200 1625);
DISPLAY 1.595745 (-5200 1625);
PAINT GREEN (-5200 1625);
DISPLAY INVISIBLE (-5200 1625);
FORCEPROP 1 LAST PATH I26
J 0
(-5527 1750);
DISPLAY 0.872340 (-5527 1750);
PAINT GREEN (-5527 1750);
DISPLAY INVISIBLE (-5527 1750);
FORCEADD TAP..6
(-5525 1800);
FORCEPROP 3 LASTPIN (-5475 1800) SIG_NAME M_B_DQ<6>
J 0
(-5465 1810);
DISPLAY 0.659574 (-5465 1810);
PAINT MONO (-5465 1810);
DISPLAY INVISIBLE (-5465 1810);
FORCEPROP 1 LASTPIN (-5475 1800) BN 6
J 0
(-5527 1808);
DISPLAY 0.617021 (-5527 1808);
PAINT PINK (-5527 1808);
FORCEPROP 2 LAST CDS_LIB mstr_standard
J 0
(-5525 1800);
PAINT MONO (-5525 1800);
DISPLAY INVISIBLE (-5525 1800);
FORCEPROP 1 LAST BODY_TYPE PLUMBING
J 0
(-5525 1750);
DISPLAY 1.595745 (-5525 1750);
PAINT GREEN (-5525 1750);
DISPLAY INVISIBLE (-5525 1750);
FORCEPROP 1 LAST HDL_TAP TRUE
J 0
(-5200 1675);
DISPLAY 1.595745 (-5200 1675);
PAINT GREEN (-5200 1675);
DISPLAY INVISIBLE (-5200 1675);
FORCEPROP 1 LAST PATH I27
J 0
(-5527 1800);
DISPLAY 0.872340 (-5527 1800);
PAINT GREEN (-5527 1800);
DISPLAY INVISIBLE (-5527 1800);
FORCEADD TAP..6
(-5525 1850);
FORCEPROP 3 LASTPIN (-5475 1850) SIG_NAME M_B_DQ<7>
J 0
(-5465 1860);
DISPLAY 0.659574 (-5465 1860);
PAINT MONO (-5465 1860);
DISPLAY INVISIBLE (-5465 1860);
FORCEPROP 1 LASTPIN (-5475 1850) BN 7
J 0
(-5527 1858);
DISPLAY 0.617021 (-5527 1858);
PAINT PINK (-5527 1858);
FORCEPROP 2 LAST CDS_LIB mstr_standard
J 0
(-5525 1850);
PAINT MONO (-5525 1850);
DISPLAY INVISIBLE (-5525 1850);
FORCEPROP 1 LAST BODY_TYPE PLUMBING
J 0
(-5525 1800);
DISPLAY 1.595745 (-5525 1800);
PAINT GREEN (-5525 1800);
DISPLAY INVISIBLE (-5525 1800);
FORCEPROP 1 LAST HDL_TAP TRUE
J 0
(-5200 1725);
DISPLAY 1.595745 (-5200 1725);
PAINT GREEN (-5200 1725);
DISPLAY INVISIBLE (-5200 1725);
FORCEPROP 1 LAST PATH I28
J 0
(-5527 1850);
DISPLAY 0.872340 (-5527 1850);
PAINT GREEN (-5527 1850);
DISPLAY INVISIBLE (-5527 1850);
FORCEADD TAP..6
(-5525 1900);
FORCEPROP 3 LASTPIN (-5475 1900) SIG_NAME M_B_DQ<8>
J 0
(-5465 1910);
DISPLAY 0.659574 (-5465 1910);
PAINT MONO (-5465 1910);
DISPLAY INVISIBLE (-5465 1910);
FORCEPROP 1 LASTPIN (-5475 1900) BN 8
J 0
(-5527 1908);
DISPLAY 0.617021 (-5527 1908);
PAINT PINK (-5527 1908);
FORCEPROP 2 LAST CDS_LIB mstr_standard
J 0
(-5525 1900);
PAINT MONO (-5525 1900);
DISPLAY INVISIBLE (-5525 1900);
FORCEPROP 1 LAST BODY_TYPE PLUMBING
J 0
(-5525 1850);
DISPLAY 1.595745 (-5525 1850);
PAINT GREEN (-5525 1850);
DISPLAY INVISIBLE (-5525 1850);
FORCEPROP 1 LAST HDL_TAP TRUE
J 0
(-5200 1775);
DISPLAY 1.595745 (-5200 1775);
PAINT GREEN (-5200 1775);
DISPLAY INVISIBLE (-5200 1775);
FORCEPROP 1 LAST PATH I29
J 0
(-5527 1900);
DISPLAY 0.872340 (-5527 1900);
PAINT GREEN (-5527 1900);
DISPLAY INVISIBLE (-5527 1900);
FORCEADD OFFPAGE..5
(-6375 1000);
FORCEPROP 2 LAST $XR0 45 
J 0
(-6629 1000);
DISPLAY 0.638298 (-6629 1000);
PAINT MONO (-6629 1000);
FORCEPROP 2 LAST $XR1 46 
J 0
(-6719 1000);
DISPLAY 0.638298 (-6719 1000);
PAINT MONO (-6719 1000);
FORCEPROP 2 LAST CDS_LIB mstr_standard
J 0
(-6375 1000);
PAINT MONO (-6375 1000);
DISPLAY INVISIBLE (-6375 1000);
FORCEPROP 1 LAST OFFPAGE TRUE
J 0
(-6050 875);
DISPLAY 1.170213 (-6050 875);
PAINT GREEN (-6050 875);
DISPLAY INVISIBLE (-6050 875);
FORCEPROP 1 LAST COMMENT_BODY TRUE
J 0
(-6275 925);
DISPLAY 1.170213 (-6275 925);
PAINT GREEN (-6275 925);
DISPLAY INVISIBLE (-6275 925);
FORCEPROP 2 LAST PATH I3
J 0
(-6325 1075);
DISPLAY 1.021277 (-6325 1075);
PAINT ORANGE (-6325 1075);
DISPLAY INVISIBLE (-6325 1075);
FORCEADD TAP..6
(-5525 2000);
FORCEPROP 3 LASTPIN (-5475 2000) SIG_NAME M_B_DQ<10>
J 0
(-5465 2010);
DISPLAY 0.659574 (-5465 2010);
PAINT MONO (-5465 2010);
DISPLAY INVISIBLE (-5465 2010);
FORCEPROP 1 LASTPIN (-5475 2000) BN 10
J 0
(-5527 2008);
DISPLAY 0.617021 (-5527 2008);
PAINT PINK (-5527 2008);
FORCEPROP 2 LAST CDS_LIB mstr_standard
J 0
(-5525 2000);
PAINT MONO (-5525 2000);
DISPLAY INVISIBLE (-5525 2000);
FORCEPROP 1 LAST BODY_TYPE PLUMBING
J 0
(-5525 1950);
DISPLAY 1.595745 (-5525 1950);
PAINT GREEN (-5525 1950);
DISPLAY INVISIBLE (-5525 1950);
FORCEPROP 1 LAST HDL_TAP TRUE
J 0
(-5200 1875);
DISPLAY 1.595745 (-5200 1875);
PAINT GREEN (-5200 1875);
DISPLAY INVISIBLE (-5200 1875);
FORCEPROP 1 LAST PATH I31
J 0
(-5527 2000);
DISPLAY 0.872340 (-5527 2000);
PAINT GREEN (-5527 2000);
DISPLAY INVISIBLE (-5527 2000);
FORCEADD TAP..6
(-5525 1950);
FORCEPROP 3 LASTPIN (-5475 1950) SIG_NAME M_B_DQ<9>
J 0
(-5465 1960);
DISPLAY 0.659574 (-5465 1960);
PAINT MONO (-5465 1960);
DISPLAY INVISIBLE (-5465 1960);
FORCEPROP 1 LASTPIN (-5475 1950) BN 9
J 0
(-5527 1958);
DISPLAY 0.617021 (-5527 1958);
PAINT PINK (-5527 1958);
FORCEPROP 2 LAST CDS_LIB mstr_standard
J 0
(-5525 1950);
PAINT MONO (-5525 1950);
DISPLAY INVISIBLE (-5525 1950);
FORCEPROP 1 LAST BODY_TYPE PLUMBING
J 0
(-5525 1900);
DISPLAY 1.595745 (-5525 1900);
PAINT GREEN (-5525 1900);
DISPLAY INVISIBLE (-5525 1900);
FORCEPROP 1 LAST HDL_TAP TRUE
J 0
(-5200 1825);
DISPLAY 1.595745 (-5200 1825);
PAINT GREEN (-5200 1825);
DISPLAY INVISIBLE (-5200 1825);
FORCEPROP 1 LAST PATH I32
J 0
(-5527 1950);
DISPLAY 0.872340 (-5527 1950);
PAINT GREEN (-5527 1950);
DISPLAY INVISIBLE (-5527 1950);
FORCEADD TAP..6
(-5525 2100);
FORCEPROP 3 LASTPIN (-5475 2100) SIG_NAME M_B_DQ<12>
J 0
(-5465 2110);
DISPLAY 0.659574 (-5465 2110);
PAINT MONO (-5465 2110);
DISPLAY INVISIBLE (-5465 2110);
FORCEPROP 1 LASTPIN (-5475 2100) BN 12
J 0
(-5527 2108);
DISPLAY 0.617021 (-5527 2108);
PAINT PINK (-5527 2108);
FORCEPROP 2 LAST CDS_LIB mstr_standard
J 0
(-5525 2100);
PAINT MONO (-5525 2100);
DISPLAY INVISIBLE (-5525 2100);
FORCEPROP 1 LAST BODY_TYPE PLUMBING
J 0
(-5525 2050);
DISPLAY 1.595745 (-5525 2050);
PAINT GREEN (-5525 2050);
DISPLAY INVISIBLE (-5525 2050);
FORCEPROP 1 LAST HDL_TAP TRUE
J 0
(-5200 1975);
DISPLAY 1.595745 (-5200 1975);
PAINT GREEN (-5200 1975);
DISPLAY INVISIBLE (-5200 1975);
FORCEPROP 1 LAST PATH I33
J 0
(-5527 2100);
DISPLAY 0.872340 (-5527 2100);
PAINT GREEN (-5527 2100);
DISPLAY INVISIBLE (-5527 2100);
FORCEADD TAP..6
(-5525 2150);
FORCEPROP 3 LASTPIN (-5475 2150) SIG_NAME M_B_DQ<13>
J 0
(-5465 2160);
DISPLAY 0.659574 (-5465 2160);
PAINT MONO (-5465 2160);
DISPLAY INVISIBLE (-5465 2160);
FORCEPROP 1 LASTPIN (-5475 2150) BN 13
J 0
(-5527 2158);
DISPLAY 0.617021 (-5527 2158);
PAINT PINK (-5527 2158);
FORCEPROP 2 LAST CDS_LIB mstr_standard
J 0
(-5525 2150);
PAINT MONO (-5525 2150);
DISPLAY INVISIBLE (-5525 2150);
FORCEPROP 1 LAST BODY_TYPE PLUMBING
J 0
(-5525 2100);
DISPLAY 1.595745 (-5525 2100);
PAINT GREEN (-5525 2100);
DISPLAY INVISIBLE (-5525 2100);
FORCEPROP 1 LAST HDL_TAP TRUE
J 0
(-5200 2025);
DISPLAY 1.595745 (-5200 2025);
PAINT GREEN (-5200 2025);
DISPLAY INVISIBLE (-5200 2025);
FORCEPROP 1 LAST PATH I34
J 0
(-5527 2150);
DISPLAY 0.872340 (-5527 2150);
PAINT GREEN (-5527 2150);
DISPLAY INVISIBLE (-5527 2150);
FORCEADD TAP..6
(-5525 2050);
FORCEPROP 3 LASTPIN (-5475 2050) SIG_NAME M_B_DQ<11>
J 0
(-5465 2060);
DISPLAY 0.659574 (-5465 2060);
PAINT MONO (-5465 2060);
DISPLAY INVISIBLE (-5465 2060);
FORCEPROP 1 LASTPIN (-5475 2050) BN 11
J 0
(-5527 2058);
DISPLAY 0.617021 (-5527 2058);
PAINT PINK (-5527 2058);
FORCEPROP 2 LAST CDS_LIB mstr_standard
J 0
(-5525 2050);
PAINT MONO (-5525 2050);
DISPLAY INVISIBLE (-5525 2050);
FORCEPROP 1 LAST BODY_TYPE PLUMBING
J 0
(-5525 2000);
DISPLAY 1.595745 (-5525 2000);
PAINT GREEN (-5525 2000);
DISPLAY INVISIBLE (-5525 2000);
FORCEPROP 1 LAST HDL_TAP TRUE
J 0
(-5200 1925);
DISPLAY 1.595745 (-5200 1925);
PAINT GREEN (-5200 1925);
DISPLAY INVISIBLE (-5200 1925);
FORCEPROP 1 LAST PATH I35
J 0
(-5527 2050);
DISPLAY 0.872340 (-5527 2050);
PAINT GREEN (-5527 2050);
DISPLAY INVISIBLE (-5527 2050);
FORCEADD TAP..6
(-5525 2200);
FORCEPROP 3 LASTPIN (-5475 2200) SIG_NAME M_B_DQ<14>
J 0
(-5465 2210);
DISPLAY 0.659574 (-5465 2210);
PAINT MONO (-5465 2210);
DISPLAY INVISIBLE (-5465 2210);
FORCEPROP 1 LASTPIN (-5475 2200) BN 14
J 0
(-5527 2208);
DISPLAY 0.617021 (-5527 2208);
PAINT PINK (-5527 2208);
FORCEPROP 2 LAST CDS_LIB mstr_standard
J 0
(-5525 2200);
PAINT MONO (-5525 2200);
DISPLAY INVISIBLE (-5525 2200);
FORCEPROP 1 LAST BODY_TYPE PLUMBING
J 0
(-5525 2150);
DISPLAY 1.595745 (-5525 2150);
PAINT GREEN (-5525 2150);
DISPLAY INVISIBLE (-5525 2150);
FORCEPROP 1 LAST HDL_TAP TRUE
J 0
(-5200 2075);
DISPLAY 1.595745 (-5200 2075);
PAINT GREEN (-5200 2075);
DISPLAY INVISIBLE (-5200 2075);
FORCEPROP 1 LAST PATH I36
J 0
(-5527 2200);
DISPLAY 0.872340 (-5527 2200);
PAINT GREEN (-5527 2200);
DISPLAY INVISIBLE (-5527 2200);
FORCEADD TAP..6
(-5525 2250);
FORCEPROP 3 LASTPIN (-5475 2250) SIG_NAME M_B_DQ<15>
J 0
(-5465 2260);
DISPLAY 0.659574 (-5465 2260);
PAINT MONO (-5465 2260);
DISPLAY INVISIBLE (-5465 2260);
FORCEPROP 1 LASTPIN (-5475 2250) BN 15
J 0
(-5527 2258);
DISPLAY 0.617021 (-5527 2258);
PAINT PINK (-5527 2258);
FORCEPROP 2 LAST CDS_LIB mstr_standard
J 0
(-5525 2250);
PAINT MONO (-5525 2250);
DISPLAY INVISIBLE (-5525 2250);
FORCEPROP 1 LAST BODY_TYPE PLUMBING
J 0
(-5525 2200);
DISPLAY 1.595745 (-5525 2200);
PAINT GREEN (-5525 2200);
DISPLAY INVISIBLE (-5525 2200);
FORCEPROP 1 LAST HDL_TAP TRUE
J 0
(-5200 2125);
DISPLAY 1.595745 (-5200 2125);
PAINT GREEN (-5200 2125);
DISPLAY INVISIBLE (-5200 2125);
FORCEPROP 1 LAST PATH I37
J 0
(-5527 2250);
DISPLAY 0.872340 (-5527 2250);
PAINT GREEN (-5527 2250);
DISPLAY INVISIBLE (-5527 2250);
FORCEADD TAP..6
(-5525 2300);
FORCEPROP 3 LASTPIN (-5475 2300) SIG_NAME M_B_DQ<16>
J 0
(-5465 2310);
DISPLAY 0.659574 (-5465 2310);
PAINT MONO (-5465 2310);
DISPLAY INVISIBLE (-5465 2310);
FORCEPROP 1 LASTPIN (-5475 2300) BN 16
J 0
(-5527 2308);
DISPLAY 0.617021 (-5527 2308);
PAINT PINK (-5527 2308);
FORCEPROP 2 LAST CDS_LIB mstr_standard
J 0
(-5525 2300);
PAINT MONO (-5525 2300);
DISPLAY INVISIBLE (-5525 2300);
FORCEPROP 1 LAST BODY_TYPE PLUMBING
J 0
(-5525 2250);
DISPLAY 1.595745 (-5525 2250);
PAINT GREEN (-5525 2250);
DISPLAY INVISIBLE (-5525 2250);
FORCEPROP 1 LAST HDL_TAP TRUE
J 0
(-5200 2175);
DISPLAY 1.595745 (-5200 2175);
PAINT GREEN (-5200 2175);
DISPLAY INVISIBLE (-5200 2175);
FORCEPROP 1 LAST PATH I38
J 0
(-5527 2300);
DISPLAY 0.872340 (-5527 2300);
PAINT GREEN (-5527 2300);
DISPLAY INVISIBLE (-5527 2300);
FORCEADD TAP..6
(-5525 2350);
FORCEPROP 3 LASTPIN (-5475 2350) SIG_NAME M_B_DQ<17>
J 0
(-5465 2360);
DISPLAY 0.659574 (-5465 2360);
PAINT MONO (-5465 2360);
DISPLAY INVISIBLE (-5465 2360);
FORCEPROP 1 LASTPIN (-5475 2350) BN 17
J 0
(-5527 2358);
DISPLAY 0.617021 (-5527 2358);
PAINT PINK (-5527 2358);
FORCEPROP 2 LAST CDS_LIB mstr_standard
J 0
(-5525 2350);
PAINT MONO (-5525 2350);
DISPLAY INVISIBLE (-5525 2350);
FORCEPROP 1 LAST BODY_TYPE PLUMBING
J 0
(-5525 2300);
DISPLAY 1.595745 (-5525 2300);
PAINT GREEN (-5525 2300);
DISPLAY INVISIBLE (-5525 2300);
FORCEPROP 1 LAST HDL_TAP TRUE
J 0
(-5200 2225);
DISPLAY 1.595745 (-5200 2225);
PAINT GREEN (-5200 2225);
DISPLAY INVISIBLE (-5200 2225);
FORCEPROP 1 LAST PATH I39
J 0
(-5527 2350);
DISPLAY 0.872340 (-5527 2350);
PAINT GREEN (-5527 2350);
DISPLAY INVISIBLE (-5527 2350);
FORCEADD OFFPAGE..6
(-6375 1450);
FORCEPROP 2 LAST $XR0 45 
J 0
(-6654 1450);
DISPLAY 0.638298 (-6654 1450);
PAINT MONO (-6654 1450);
FORCEPROP 2 LAST $XR1 46 
J 0
(-6744 1450);
DISPLAY 0.638298 (-6744 1450);
PAINT MONO (-6744 1450);
FORCEPROP 2 LAST CDS_LIB mstr_standard
J 0
(-6375 1450);
PAINT MONO (-6375 1450);
DISPLAY INVISIBLE (-6375 1450);
FORCEPROP 1 LAST OFFPAGE TRUE
J 0
(-6050 1325);
DISPLAY 1.170213 (-6050 1325);
PAINT GREEN (-6050 1325);
DISPLAY INVISIBLE (-6050 1325);
FORCEPROP 1 LAST COMMENT_BODY TRUE
J 0
(-6275 1375);
DISPLAY 1.170213 (-6275 1375);
PAINT GREEN (-6275 1375);
DISPLAY INVISIBLE (-6275 1375);
FORCEPROP 2 LAST PATH I4
J 0
(-6325 1525);
DISPLAY 1.021277 (-6325 1525);
PAINT ORANGE (-6325 1525);
DISPLAY INVISIBLE (-6325 1525);
FORCEADD TAP..6
(-5525 2400);
FORCEPROP 3 LASTPIN (-5475 2400) SIG_NAME M_B_DQ<18>
J 0
(-5465 2410);
DISPLAY 0.659574 (-5465 2410);
PAINT MONO (-5465 2410);
DISPLAY INVISIBLE (-5465 2410);
FORCEPROP 1 LASTPIN (-5475 2400) BN 18
J 0
(-5527 2408);
DISPLAY 0.617021 (-5527 2408);
PAINT PINK (-5527 2408);
FORCEPROP 2 LAST CDS_LIB mstr_standard
J 0
(-5525 2400);
PAINT MONO (-5525 2400);
DISPLAY INVISIBLE (-5525 2400);
FORCEPROP 1 LAST BODY_TYPE PLUMBING
J 0
(-5525 2350);
DISPLAY 1.595745 (-5525 2350);
PAINT GREEN (-5525 2350);
DISPLAY INVISIBLE (-5525 2350);
FORCEPROP 1 LAST HDL_TAP TRUE
J 0
(-5200 2275);
DISPLAY 1.595745 (-5200 2275);
PAINT GREEN (-5200 2275);
DISPLAY INVISIBLE (-5200 2275);
FORCEPROP 1 LAST PATH I40
J 0
(-5527 2400);
DISPLAY 0.872340 (-5527 2400);
PAINT GREEN (-5527 2400);
DISPLAY INVISIBLE (-5527 2400);
FORCEADD TAP..6
(-5525 2500);
FORCEPROP 3 LASTPIN (-5475 2500) SIG_NAME M_B_DQ<20>
J 0
(-5465 2510);
DISPLAY 0.659574 (-5465 2510);
PAINT MONO (-5465 2510);
DISPLAY INVISIBLE (-5465 2510);
FORCEPROP 1 LASTPIN (-5475 2500) BN 20
J 0
(-5527 2508);
DISPLAY 0.617021 (-5527 2508);
PAINT PINK (-5527 2508);
FORCEPROP 2 LAST CDS_LIB mstr_standard
J 0
(-5525 2500);
PAINT MONO (-5525 2500);
DISPLAY INVISIBLE (-5525 2500);
FORCEPROP 1 LAST BODY_TYPE PLUMBING
J 0
(-5525 2450);
DISPLAY 1.595745 (-5525 2450);
PAINT GREEN (-5525 2450);
DISPLAY INVISIBLE (-5525 2450);
FORCEPROP 1 LAST HDL_TAP TRUE
J 0
(-5200 2375);
DISPLAY 1.595745 (-5200 2375);
PAINT GREEN (-5200 2375);
DISPLAY INVISIBLE (-5200 2375);
FORCEPROP 1 LAST PATH I41
J 0
(-5527 2500);
DISPLAY 0.872340 (-5527 2500);
PAINT GREEN (-5527 2500);
DISPLAY INVISIBLE (-5527 2500);
FORCEADD TAP..6
(-5525 2450);
FORCEPROP 3 LASTPIN (-5475 2450) SIG_NAME M_B_DQ<19>
J 0
(-5465 2460);
DISPLAY 0.659574 (-5465 2460);
PAINT MONO (-5465 2460);
DISPLAY INVISIBLE (-5465 2460);
FORCEPROP 1 LASTPIN (-5475 2450) BN 19
J 0
(-5527 2458);
DISPLAY 0.617021 (-5527 2458);
PAINT PINK (-5527 2458);
FORCEPROP 2 LAST CDS_LIB mstr_standard
J 0
(-5525 2450);
PAINT MONO (-5525 2450);
DISPLAY INVISIBLE (-5525 2450);
FORCEPROP 1 LAST BODY_TYPE PLUMBING
J 0
(-5525 2400);
DISPLAY 1.595745 (-5525 2400);
PAINT GREEN (-5525 2400);
DISPLAY INVISIBLE (-5525 2400);
FORCEPROP 1 LAST HDL_TAP TRUE
J 0
(-5200 2325);
DISPLAY 1.595745 (-5200 2325);
PAINT GREEN (-5200 2325);
DISPLAY INVISIBLE (-5200 2325);
FORCEPROP 1 LAST PATH I42
J 0
(-5527 2450);
DISPLAY 0.872340 (-5527 2450);
PAINT GREEN (-5527 2450);
DISPLAY INVISIBLE (-5527 2450);
FORCEADD TAP..6
(-5525 2550);
FORCEPROP 3 LASTPIN (-5475 2550) SIG_NAME M_B_DQ<21>
J 0
(-5465 2560);
DISPLAY 0.659574 (-5465 2560);
PAINT MONO (-5465 2560);
DISPLAY INVISIBLE (-5465 2560);
FORCEPROP 1 LASTPIN (-5475 2550) BN 21
J 0
(-5527 2558);
DISPLAY 0.617021 (-5527 2558);
PAINT PINK (-5527 2558);
FORCEPROP 2 LAST CDS_LIB mstr_standard
J 0
(-5525 2550);
PAINT MONO (-5525 2550);
DISPLAY INVISIBLE (-5525 2550);
FORCEPROP 1 LAST BODY_TYPE PLUMBING
J 0
(-5525 2500);
DISPLAY 1.595745 (-5525 2500);
PAINT GREEN (-5525 2500);
DISPLAY INVISIBLE (-5525 2500);
FORCEPROP 1 LAST HDL_TAP TRUE
J 0
(-5200 2425);
DISPLAY 1.595745 (-5200 2425);
PAINT GREEN (-5200 2425);
DISPLAY INVISIBLE (-5200 2425);
FORCEPROP 1 LAST PATH I43
J 0
(-5527 2550);
DISPLAY 0.872340 (-5527 2550);
PAINT GREEN (-5527 2550);
DISPLAY INVISIBLE (-5527 2550);
FORCEADD TAP..6
(-5525 2600);
FORCEPROP 3 LASTPIN (-5475 2600) SIG_NAME M_B_DQ<22>
J 0
(-5465 2610);
DISPLAY 0.659574 (-5465 2610);
PAINT MONO (-5465 2610);
DISPLAY INVISIBLE (-5465 2610);
FORCEPROP 1 LASTPIN (-5475 2600) BN 22
J 0
(-5527 2608);
DISPLAY 0.617021 (-5527 2608);
PAINT PINK (-5527 2608);
FORCEPROP 2 LAST CDS_LIB mstr_standard
J 0
(-5525 2600);
PAINT MONO (-5525 2600);
DISPLAY INVISIBLE (-5525 2600);
FORCEPROP 1 LAST BODY_TYPE PLUMBING
J 0
(-5525 2550);
DISPLAY 1.595745 (-5525 2550);
PAINT GREEN (-5525 2550);
DISPLAY INVISIBLE (-5525 2550);
FORCEPROP 1 LAST HDL_TAP TRUE
J 0
(-5200 2475);
DISPLAY 1.595745 (-5200 2475);
PAINT GREEN (-5200 2475);
DISPLAY INVISIBLE (-5200 2475);
FORCEPROP 1 LAST PATH I44
J 0
(-5527 2600);
DISPLAY 0.872340 (-5527 2600);
PAINT GREEN (-5527 2600);
DISPLAY INVISIBLE (-5527 2600);
FORCEADD TAP..6
(-5525 2650);
FORCEPROP 3 LASTPIN (-5475 2650) SIG_NAME M_B_DQ<23>
J 0
(-5465 2660);
DISPLAY 0.659574 (-5465 2660);
PAINT MONO (-5465 2660);
DISPLAY INVISIBLE (-5465 2660);
FORCEPROP 1 LASTPIN (-5475 2650) BN 23
J 0
(-5527 2658);
DISPLAY 0.617021 (-5527 2658);
PAINT PINK (-5527 2658);
FORCEPROP 2 LAST CDS_LIB mstr_standard
J 0
(-5525 2650);
PAINT MONO (-5525 2650);
DISPLAY INVISIBLE (-5525 2650);
FORCEPROP 1 LAST BODY_TYPE PLUMBING
J 0
(-5525 2600);
DISPLAY 1.595745 (-5525 2600);
PAINT GREEN (-5525 2600);
DISPLAY INVISIBLE (-5525 2600);
FORCEPROP 1 LAST HDL_TAP TRUE
J 0
(-5200 2525);
DISPLAY 1.595745 (-5200 2525);
PAINT GREEN (-5200 2525);
DISPLAY INVISIBLE (-5200 2525);
FORCEPROP 1 LAST PATH I45
J 0
(-5527 2650);
DISPLAY 0.872340 (-5527 2650);
PAINT GREEN (-5527 2650);
DISPLAY INVISIBLE (-5527 2650);
FORCEADD TAP..6
(-5525 2700);
FORCEPROP 3 LASTPIN (-5475 2700) SIG_NAME M_B_DQ<24>
J 0
(-5465 2710);
DISPLAY 0.659574 (-5465 2710);
PAINT MONO (-5465 2710);
DISPLAY INVISIBLE (-5465 2710);
FORCEPROP 1 LASTPIN (-5475 2700) BN 24
J 0
(-5527 2708);
DISPLAY 0.617021 (-5527 2708);
PAINT PINK (-5527 2708);
FORCEPROP 2 LAST CDS_LIB mstr_standard
J 0
(-5525 2700);
PAINT MONO (-5525 2700);
DISPLAY INVISIBLE (-5525 2700);
FORCEPROP 1 LAST BODY_TYPE PLUMBING
J 0
(-5525 2650);
DISPLAY 1.595745 (-5525 2650);
PAINT GREEN (-5525 2650);
DISPLAY INVISIBLE (-5525 2650);
FORCEPROP 1 LAST HDL_TAP TRUE
J 0
(-5200 2575);
DISPLAY 1.595745 (-5200 2575);
PAINT GREEN (-5200 2575);
DISPLAY INVISIBLE (-5200 2575);
FORCEPROP 1 LAST PATH I46
J 0
(-5527 2700);
DISPLAY 0.872340 (-5527 2700);
PAINT GREEN (-5527 2700);
DISPLAY INVISIBLE (-5527 2700);
FORCEADD TAP..6
(-5525 2750);
FORCEPROP 3 LASTPIN (-5475 2750) SIG_NAME M_B_DQ<25>
J 0
(-5465 2760);
DISPLAY 0.659574 (-5465 2760);
PAINT MONO (-5465 2760);
DISPLAY INVISIBLE (-5465 2760);
FORCEPROP 1 LASTPIN (-5475 2750) BN 25
J 0
(-5527 2758);
DISPLAY 0.617021 (-5527 2758);
PAINT PINK (-5527 2758);
FORCEPROP 2 LAST CDS_LIB mstr_standard
J 0
(-5525 2750);
PAINT MONO (-5525 2750);
DISPLAY INVISIBLE (-5525 2750);
FORCEPROP 1 LAST BODY_TYPE PLUMBING
J 0
(-5525 2700);
DISPLAY 1.595745 (-5525 2700);
PAINT GREEN (-5525 2700);
DISPLAY INVISIBLE (-5525 2700);
FORCEPROP 1 LAST HDL_TAP TRUE
J 0
(-5200 2625);
DISPLAY 1.595745 (-5200 2625);
PAINT GREEN (-5200 2625);
DISPLAY INVISIBLE (-5200 2625);
FORCEPROP 1 LAST PATH I47
J 0
(-5527 2750);
DISPLAY 0.872340 (-5527 2750);
PAINT GREEN (-5527 2750);
DISPLAY INVISIBLE (-5527 2750);
FORCEADD TAP..6
(-5525 2800);
FORCEPROP 3 LASTPIN (-5475 2800) SIG_NAME M_B_DQ<26>
J 0
(-5465 2810);
DISPLAY 0.659574 (-5465 2810);
PAINT MONO (-5465 2810);
DISPLAY INVISIBLE (-5465 2810);
FORCEPROP 1 LASTPIN (-5475 2800) BN 26
J 0
(-5527 2808);
DISPLAY 0.617021 (-5527 2808);
PAINT PINK (-5527 2808);
FORCEPROP 2 LAST CDS_LIB mstr_standard
J 0
(-5525 2800);
PAINT MONO (-5525 2800);
DISPLAY INVISIBLE (-5525 2800);
FORCEPROP 1 LAST BODY_TYPE PLUMBING
J 0
(-5525 2750);
DISPLAY 1.595745 (-5525 2750);
PAINT GREEN (-5525 2750);
DISPLAY INVISIBLE (-5525 2750);
FORCEPROP 1 LAST HDL_TAP TRUE
J 0
(-5200 2675);
DISPLAY 1.595745 (-5200 2675);
PAINT GREEN (-5200 2675);
DISPLAY INVISIBLE (-5200 2675);
FORCEPROP 1 LAST PATH I48
J 0
(-5527 2800);
DISPLAY 0.872340 (-5527 2800);
PAINT GREEN (-5527 2800);
DISPLAY INVISIBLE (-5527 2800);
FORCEADD TAP..6
(-5525 2850);
FORCEPROP 3 LASTPIN (-5475 2850) SIG_NAME M_B_DQ<27>
J 0
(-5465 2860);
DISPLAY 0.659574 (-5465 2860);
PAINT MONO (-5465 2860);
DISPLAY INVISIBLE (-5465 2860);
FORCEPROP 1 LASTPIN (-5475 2850) BN 27
J 0
(-5527 2858);
DISPLAY 0.617021 (-5527 2858);
PAINT PINK (-5527 2858);
FORCEPROP 2 LAST CDS_LIB mstr_standard
J 0
(-5525 2850);
PAINT MONO (-5525 2850);
DISPLAY INVISIBLE (-5525 2850);
FORCEPROP 1 LAST BODY_TYPE PLUMBING
J 0
(-5525 2800);
DISPLAY 1.595745 (-5525 2800);
PAINT GREEN (-5525 2800);
DISPLAY INVISIBLE (-5525 2800);
FORCEPROP 1 LAST HDL_TAP TRUE
J 0
(-5200 2725);
DISPLAY 1.595745 (-5200 2725);
PAINT GREEN (-5200 2725);
DISPLAY INVISIBLE (-5200 2725);
FORCEPROP 1 LAST PATH I49
J 0
(-5527 2850);
DISPLAY 0.872340 (-5527 2850);
PAINT GREEN (-5527 2850);
DISPLAY INVISIBLE (-5527 2850);
FORCEADD TAP..6
(-5525 600);
FORCEPROP 3 LASTPIN (-5475 600) SIG_NAME M_B_CLK_DN<0>
J 0
(-5465 610);
DISPLAY 0.659574 (-5465 610);
PAINT MONO (-5465 610);
DISPLAY INVISIBLE (-5465 610);
FORCEPROP 1 LASTPIN (-5475 600) BN 0
J 0
(-5527 608);
DISPLAY 0.617021 (-5527 608);
PAINT PINK (-5527 608);
FORCEPROP 2 LAST CDS_LIB mstr_standard
J 0
(-5525 600);
PAINT MONO (-5525 600);
DISPLAY INVISIBLE (-5525 600);
FORCEPROP 1 LAST BODY_TYPE PLUMBING
J 0
(-5525 550);
DISPLAY 1.595745 (-5525 550);
PAINT GREEN (-5525 550);
DISPLAY INVISIBLE (-5525 550);
FORCEPROP 1 LAST HDL_TAP TRUE
J 0
(-5200 475);
DISPLAY 1.595745 (-5200 475);
PAINT GREEN (-5200 475);
DISPLAY INVISIBLE (-5200 475);
FORCEPROP 1 LAST PATH I5
J 0
(-5527 600);
DISPLAY 0.872340 (-5527 600);
PAINT GREEN (-5527 600);
DISPLAY INVISIBLE (-5527 600);
FORCEADD TAP..6
(-5525 2900);
FORCEPROP 3 LASTPIN (-5475 2900) SIG_NAME M_B_DQ<28>
J 0
(-5465 2910);
DISPLAY 0.659574 (-5465 2910);
PAINT MONO (-5465 2910);
DISPLAY INVISIBLE (-5465 2910);
FORCEPROP 1 LASTPIN (-5475 2900) BN 28
J 0
(-5527 2908);
DISPLAY 0.617021 (-5527 2908);
PAINT PINK (-5527 2908);
FORCEPROP 2 LAST CDS_LIB mstr_standard
J 0
(-5525 2900);
PAINT MONO (-5525 2900);
DISPLAY INVISIBLE (-5525 2900);
FORCEPROP 1 LAST BODY_TYPE PLUMBING
J 0
(-5525 2850);
DISPLAY 1.595745 (-5525 2850);
PAINT GREEN (-5525 2850);
DISPLAY INVISIBLE (-5525 2850);
FORCEPROP 1 LAST HDL_TAP TRUE
J 0
(-5200 2775);
DISPLAY 1.595745 (-5200 2775);
PAINT GREEN (-5200 2775);
DISPLAY INVISIBLE (-5200 2775);
FORCEPROP 1 LAST PATH I50
J 0
(-5527 2900);
DISPLAY 0.872340 (-5527 2900);
PAINT GREEN (-5527 2900);
DISPLAY INVISIBLE (-5527 2900);
FORCEADD TAP..6
(-5525 3000);
FORCEPROP 3 LASTPIN (-5475 3000) SIG_NAME M_B_DQ<30>
J 0
(-5465 3010);
DISPLAY 0.659574 (-5465 3010);
PAINT MONO (-5465 3010);
DISPLAY INVISIBLE (-5465 3010);
FORCEPROP 1 LASTPIN (-5475 3000) BN 30
J 0
(-5527 3008);
DISPLAY 0.617021 (-5527 3008);
PAINT PINK (-5527 3008);
FORCEPROP 2 LAST CDS_LIB mstr_standard
J 0
(-5525 3000);
PAINT MONO (-5525 3000);
DISPLAY INVISIBLE (-5525 3000);
FORCEPROP 1 LAST BODY_TYPE PLUMBING
J 0
(-5525 2950);
DISPLAY 1.595745 (-5525 2950);
PAINT GREEN (-5525 2950);
DISPLAY INVISIBLE (-5525 2950);
FORCEPROP 1 LAST HDL_TAP TRUE
J 0
(-5200 2875);
DISPLAY 1.595745 (-5200 2875);
PAINT GREEN (-5200 2875);
DISPLAY INVISIBLE (-5200 2875);
FORCEPROP 1 LAST PATH I51
J 0
(-5527 3000);
DISPLAY 0.872340 (-5527 3000);
PAINT GREEN (-5527 3000);
DISPLAY INVISIBLE (-5527 3000);
FORCEADD TAP..6
(-5525 2950);
FORCEPROP 3 LASTPIN (-5475 2950) SIG_NAME M_B_DQ<29>
J 0
(-5465 2960);
DISPLAY 0.659574 (-5465 2960);
PAINT MONO (-5465 2960);
DISPLAY INVISIBLE (-5465 2960);
FORCEPROP 1 LASTPIN (-5475 2950) BN 29
J 0
(-5527 2958);
DISPLAY 0.617021 (-5527 2958);
PAINT PINK (-5527 2958);
FORCEPROP 2 LAST CDS_LIB mstr_standard
J 0
(-5525 2950);
PAINT MONO (-5525 2950);
DISPLAY INVISIBLE (-5525 2950);
FORCEPROP 1 LAST BODY_TYPE PLUMBING
J 0
(-5525 2900);
DISPLAY 1.595745 (-5525 2900);
PAINT GREEN (-5525 2900);
DISPLAY INVISIBLE (-5525 2900);
FORCEPROP 1 LAST HDL_TAP TRUE
J 0
(-5200 2825);
DISPLAY 1.595745 (-5200 2825);
PAINT GREEN (-5200 2825);
DISPLAY INVISIBLE (-5200 2825);
FORCEPROP 1 LAST PATH I52
J 0
(-5527 2950);
DISPLAY 0.872340 (-5527 2950);
PAINT GREEN (-5527 2950);
DISPLAY INVISIBLE (-5527 2950);
FORCEADD TAP..6
(-5525 3050);
FORCEPROP 3 LASTPIN (-5475 3050) SIG_NAME M_B_DQ<31>
J 0
(-5465 3060);
DISPLAY 0.659574 (-5465 3060);
PAINT MONO (-5465 3060);
DISPLAY INVISIBLE (-5465 3060);
FORCEPROP 1 LASTPIN (-5475 3050) BN 31
J 0
(-5527 3058);
DISPLAY 0.617021 (-5527 3058);
PAINT PINK (-5527 3058);
FORCEPROP 2 LAST CDS_LIB mstr_standard
J 0
(-5525 3050);
PAINT MONO (-5525 3050);
DISPLAY INVISIBLE (-5525 3050);
FORCEPROP 1 LAST BODY_TYPE PLUMBING
J 0
(-5525 3000);
DISPLAY 1.595745 (-5525 3000);
PAINT GREEN (-5525 3000);
DISPLAY INVISIBLE (-5525 3000);
FORCEPROP 1 LAST HDL_TAP TRUE
J 0
(-5200 2925);
DISPLAY 1.595745 (-5200 2925);
PAINT GREEN (-5200 2925);
DISPLAY INVISIBLE (-5200 2925);
FORCEPROP 1 LAST PATH I53
J 0
(-5527 3050);
DISPLAY 0.872340 (-5527 3050);
PAINT GREEN (-5527 3050);
DISPLAY INVISIBLE (-5527 3050);
FORCEADD TAP..6
(-5525 3100);
FORCEPROP 3 LASTPIN (-5475 3100) SIG_NAME M_B_DQ<32>
J 0
(-5465 3110);
DISPLAY 0.659574 (-5465 3110);
PAINT MONO (-5465 3110);
DISPLAY INVISIBLE (-5465 3110);
FORCEPROP 1 LASTPIN (-5475 3100) BN 32
J 0
(-5527 3108);
DISPLAY 0.617021 (-5527 3108);
PAINT PINK (-5527 3108);
FORCEPROP 2 LAST CDS_LIB mstr_standard
J 0
(-5525 3100);
PAINT MONO (-5525 3100);
DISPLAY INVISIBLE (-5525 3100);
FORCEPROP 1 LAST BODY_TYPE PLUMBING
J 0
(-5525 3050);
DISPLAY 1.595745 (-5525 3050);
PAINT GREEN (-5525 3050);
DISPLAY INVISIBLE (-5525 3050);
FORCEPROP 1 LAST HDL_TAP TRUE
J 0
(-5200 2975);
DISPLAY 1.595745 (-5200 2975);
PAINT GREEN (-5200 2975);
DISPLAY INVISIBLE (-5200 2975);
FORCEPROP 1 LAST PATH I54
J 0
(-5527 3100);
DISPLAY 0.872340 (-5527 3100);
PAINT GREEN (-5527 3100);
DISPLAY INVISIBLE (-5527 3100);
FORCEADD TAP..6
(-5525 3150);
FORCEPROP 3 LASTPIN (-5475 3150) SIG_NAME M_B_DQ<33>
J 0
(-5465 3160);
DISPLAY 0.659574 (-5465 3160);
PAINT MONO (-5465 3160);
DISPLAY INVISIBLE (-5465 3160);
FORCEPROP 1 LASTPIN (-5475 3150) BN 33
J 0
(-5527 3158);
DISPLAY 0.617021 (-5527 3158);
PAINT PINK (-5527 3158);
FORCEPROP 2 LAST CDS_LIB mstr_standard
J 0
(-5525 3150);
PAINT MONO (-5525 3150);
DISPLAY INVISIBLE (-5525 3150);
FORCEPROP 1 LAST BODY_TYPE PLUMBING
J 0
(-5525 3100);
DISPLAY 1.595745 (-5525 3100);
PAINT GREEN (-5525 3100);
DISPLAY INVISIBLE (-5525 3100);
FORCEPROP 1 LAST HDL_TAP TRUE
J 0
(-5200 3025);
DISPLAY 1.595745 (-5200 3025);
PAINT GREEN (-5200 3025);
DISPLAY INVISIBLE (-5200 3025);
FORCEPROP 1 LAST PATH I55
J 0
(-5527 3150);
DISPLAY 0.872340 (-5527 3150);
PAINT GREEN (-5527 3150);
DISPLAY INVISIBLE (-5527 3150);
FORCEADD TAP..6
(-5525 3200);
FORCEPROP 3 LASTPIN (-5475 3200) SIG_NAME M_B_DQ<34>
J 0
(-5465 3210);
DISPLAY 0.659574 (-5465 3210);
PAINT MONO (-5465 3210);
DISPLAY INVISIBLE (-5465 3210);
FORCEPROP 1 LASTPIN (-5475 3200) BN 34
J 0
(-5527 3208);
DISPLAY 0.617021 (-5527 3208);
PAINT PINK (-5527 3208);
FORCEPROP 2 LAST CDS_LIB mstr_standard
J 0
(-5525 3200);
PAINT MONO (-5525 3200);
DISPLAY INVISIBLE (-5525 3200);
FORCEPROP 1 LAST BODY_TYPE PLUMBING
J 0
(-5525 3150);
DISPLAY 1.595745 (-5525 3150);
PAINT GREEN (-5525 3150);
DISPLAY INVISIBLE (-5525 3150);
FORCEPROP 1 LAST HDL_TAP TRUE
J 0
(-5200 3075);
DISPLAY 1.595745 (-5200 3075);
PAINT GREEN (-5200 3075);
DISPLAY INVISIBLE (-5200 3075);
FORCEPROP 1 LAST PATH I56
J 0
(-5527 3200);
DISPLAY 0.872340 (-5527 3200);
PAINT GREEN (-5527 3200);
DISPLAY INVISIBLE (-5527 3200);
FORCEADD TAP..6
(-5525 3300);
FORCEPROP 3 LASTPIN (-5475 3300) SIG_NAME M_B_DQ<36>
J 0
(-5465 3310);
DISPLAY 0.659574 (-5465 3310);
PAINT MONO (-5465 3310);
DISPLAY INVISIBLE (-5465 3310);
FORCEPROP 1 LASTPIN (-5475 3300) BN 36
J 0
(-5527 3308);
DISPLAY 0.617021 (-5527 3308);
PAINT PINK (-5527 3308);
FORCEPROP 2 LAST CDS_LIB mstr_standard
J 0
(-5525 3300);
PAINT MONO (-5525 3300);
DISPLAY INVISIBLE (-5525 3300);
FORCEPROP 1 LAST BODY_TYPE PLUMBING
J 0
(-5525 3250);
DISPLAY 1.595745 (-5525 3250);
PAINT GREEN (-5525 3250);
DISPLAY INVISIBLE (-5525 3250);
FORCEPROP 1 LAST HDL_TAP TRUE
J 0
(-5200 3175);
DISPLAY 1.595745 (-5200 3175);
PAINT GREEN (-5200 3175);
DISPLAY INVISIBLE (-5200 3175);
FORCEPROP 1 LAST PATH I57
J 0
(-5527 3300);
DISPLAY 0.872340 (-5527 3300);
PAINT GREEN (-5527 3300);
DISPLAY INVISIBLE (-5527 3300);
FORCEADD TAP..6
(-5525 3250);
FORCEPROP 3 LASTPIN (-5475 3250) SIG_NAME M_B_DQ<35>
J 0
(-5465 3260);
DISPLAY 0.659574 (-5465 3260);
PAINT MONO (-5465 3260);
DISPLAY INVISIBLE (-5465 3260);
FORCEPROP 1 LASTPIN (-5475 3250) BN 35
J 0
(-5527 3258);
DISPLAY 0.617021 (-5527 3258);
PAINT PINK (-5527 3258);
FORCEPROP 2 LAST CDS_LIB mstr_standard
J 0
(-5525 3250);
PAINT MONO (-5525 3250);
DISPLAY INVISIBLE (-5525 3250);
FORCEPROP 1 LAST BODY_TYPE PLUMBING
J 0
(-5525 3200);
DISPLAY 1.595745 (-5525 3200);
PAINT GREEN (-5525 3200);
DISPLAY INVISIBLE (-5525 3200);
FORCEPROP 1 LAST HDL_TAP TRUE
J 0
(-5200 3125);
DISPLAY 1.595745 (-5200 3125);
PAINT GREEN (-5200 3125);
DISPLAY INVISIBLE (-5200 3125);
FORCEPROP 1 LAST PATH I58
J 0
(-5527 3250);
DISPLAY 0.872340 (-5527 3250);
PAINT GREEN (-5527 3250);
DISPLAY INVISIBLE (-5527 3250);
FORCEADD TAP..6
(-5525 3350);
FORCEPROP 3 LASTPIN (-5475 3350) SIG_NAME M_B_DQ<37>
J 0
(-5465 3360);
DISPLAY 0.659574 (-5465 3360);
PAINT MONO (-5465 3360);
DISPLAY INVISIBLE (-5465 3360);
FORCEPROP 1 LASTPIN (-5475 3350) BN 37
J 0
(-5527 3358);
DISPLAY 0.617021 (-5527 3358);
PAINT PINK (-5527 3358);
FORCEPROP 2 LAST CDS_LIB mstr_standard
J 0
(-5525 3350);
PAINT MONO (-5525 3350);
DISPLAY INVISIBLE (-5525 3350);
FORCEPROP 1 LAST BODY_TYPE PLUMBING
J 0
(-5525 3300);
DISPLAY 1.595745 (-5525 3300);
PAINT GREEN (-5525 3300);
DISPLAY INVISIBLE (-5525 3300);
FORCEPROP 1 LAST HDL_TAP TRUE
J 0
(-5200 3225);
DISPLAY 1.595745 (-5200 3225);
PAINT GREEN (-5200 3225);
DISPLAY INVISIBLE (-5200 3225);
FORCEPROP 1 LAST PATH I59
J 0
(-5527 3350);
DISPLAY 0.872340 (-5527 3350);
PAINT GREEN (-5527 3350);
DISPLAY INVISIBLE (-5527 3350);
FORCEADD TAP..6
(-5525 650);
FORCEPROP 3 LASTPIN (-5475 650) SIG_NAME M_B_CLK_DN<1>
J 0
(-5465 660);
DISPLAY 0.659574 (-5465 660);
PAINT MONO (-5465 660);
DISPLAY INVISIBLE (-5465 660);
FORCEPROP 1 LASTPIN (-5475 650) BN 1
J 0
(-5527 658);
DISPLAY 0.617021 (-5527 658);
PAINT PINK (-5527 658);
FORCEPROP 2 LAST CDS_LIB mstr_standard
J 0
(-5525 650);
PAINT MONO (-5525 650);
DISPLAY INVISIBLE (-5525 650);
FORCEPROP 1 LAST BODY_TYPE PLUMBING
J 0
(-5525 600);
DISPLAY 1.595745 (-5525 600);
PAINT GREEN (-5525 600);
DISPLAY INVISIBLE (-5525 600);
FORCEPROP 1 LAST HDL_TAP TRUE
J 0
(-5200 525);
DISPLAY 1.595745 (-5200 525);
PAINT GREEN (-5200 525);
DISPLAY INVISIBLE (-5200 525);
FORCEPROP 1 LAST PATH I6
J 0
(-5527 650);
DISPLAY 0.872340 (-5527 650);
PAINT GREEN (-5527 650);
DISPLAY INVISIBLE (-5527 650);
FORCEADD TAP..6
(-5525 3400);
FORCEPROP 3 LASTPIN (-5475 3400) SIG_NAME M_B_DQ<38>
J 0
(-5465 3410);
DISPLAY 0.659574 (-5465 3410);
PAINT MONO (-5465 3410);
DISPLAY INVISIBLE (-5465 3410);
FORCEPROP 1 LASTPIN (-5475 3400) BN 38
J 0
(-5527 3408);
DISPLAY 0.617021 (-5527 3408);
PAINT PINK (-5527 3408);
FORCEPROP 2 LAST CDS_LIB mstr_standard
J 0
(-5525 3400);
PAINT MONO (-5525 3400);
DISPLAY INVISIBLE (-5525 3400);
FORCEPROP 1 LAST BODY_TYPE PLUMBING
J 0
(-5525 3350);
DISPLAY 1.595745 (-5525 3350);
PAINT GREEN (-5525 3350);
DISPLAY INVISIBLE (-5525 3350);
FORCEPROP 1 LAST HDL_TAP TRUE
J 0
(-5200 3275);
DISPLAY 1.595745 (-5200 3275);
PAINT GREEN (-5200 3275);
DISPLAY INVISIBLE (-5200 3275);
FORCEPROP 1 LAST PATH I60
J 0
(-5527 3400);
DISPLAY 0.872340 (-5527 3400);
PAINT GREEN (-5527 3400);
DISPLAY INVISIBLE (-5527 3400);
FORCEADD TAP..6
(-5525 3450);
FORCEPROP 3 LASTPIN (-5475 3450) SIG_NAME M_B_DQ<39>
J 0
(-5465 3460);
DISPLAY 0.659574 (-5465 3460);
PAINT MONO (-5465 3460);
DISPLAY INVISIBLE (-5465 3460);
FORCEPROP 1 LASTPIN (-5475 3450) BN 39
J 0
(-5527 3458);
DISPLAY 0.617021 (-5527 3458);
PAINT PINK (-5527 3458);
FORCEPROP 2 LAST CDS_LIB mstr_standard
J 0
(-5525 3450);
PAINT MONO (-5525 3450);
DISPLAY INVISIBLE (-5525 3450);
FORCEPROP 1 LAST BODY_TYPE PLUMBING
J 0
(-5525 3400);
DISPLAY 1.595745 (-5525 3400);
PAINT GREEN (-5525 3400);
DISPLAY INVISIBLE (-5525 3400);
FORCEPROP 1 LAST HDL_TAP TRUE
J 0
(-5200 3325);
DISPLAY 1.595745 (-5200 3325);
PAINT GREEN (-5200 3325);
DISPLAY INVISIBLE (-5200 3325);
FORCEPROP 1 LAST PATH I61
J 0
(-5527 3450);
DISPLAY 0.872340 (-5527 3450);
PAINT GREEN (-5527 3450);
DISPLAY INVISIBLE (-5527 3450);
FORCEADD TAP..6
(-5525 3550);
FORCEPROP 3 LASTPIN (-5475 3550) SIG_NAME M_B_DQ<41>
J 0
(-5465 3560);
DISPLAY 0.659574 (-5465 3560);
PAINT MONO (-5465 3560);
DISPLAY INVISIBLE (-5465 3560);
FORCEPROP 1 LASTPIN (-5475 3550) BN 41
J 0
(-5527 3558);
DISPLAY 0.617021 (-5527 3558);
PAINT PINK (-5527 3558);
FORCEPROP 2 LAST CDS_LIB mstr_standard
J 0
(-5525 3550);
PAINT MONO (-5525 3550);
DISPLAY INVISIBLE (-5525 3550);
FORCEPROP 1 LAST BODY_TYPE PLUMBING
J 0
(-5525 3500);
DISPLAY 1.595745 (-5525 3500);
PAINT GREEN (-5525 3500);
DISPLAY INVISIBLE (-5525 3500);
FORCEPROP 1 LAST HDL_TAP TRUE
J 0
(-5200 3425);
DISPLAY 1.595745 (-5200 3425);
PAINT GREEN (-5200 3425);
DISPLAY INVISIBLE (-5200 3425);
FORCEPROP 1 LAST PATH I62
J 0
(-5527 3550);
DISPLAY 0.872340 (-5527 3550);
PAINT GREEN (-5527 3550);
DISPLAY INVISIBLE (-5527 3550);
FORCEADD TAP..6
(-5525 3500);
FORCEPROP 3 LASTPIN (-5475 3500) SIG_NAME M_B_DQ<40>
J 0
(-5465 3510);
DISPLAY 0.659574 (-5465 3510);
PAINT MONO (-5465 3510);
DISPLAY INVISIBLE (-5465 3510);
FORCEPROP 1 LASTPIN (-5475 3500) BN 40
J 0
(-5527 3508);
DISPLAY 0.617021 (-5527 3508);
PAINT PINK (-5527 3508);
FORCEPROP 2 LAST CDS_LIB mstr_standard
J 0
(-5525 3500);
PAINT MONO (-5525 3500);
DISPLAY INVISIBLE (-5525 3500);
FORCEPROP 1 LAST BODY_TYPE PLUMBING
J 0
(-5525 3450);
DISPLAY 1.595745 (-5525 3450);
PAINT GREEN (-5525 3450);
DISPLAY INVISIBLE (-5525 3450);
FORCEPROP 1 LAST HDL_TAP TRUE
J 0
(-5200 3375);
DISPLAY 1.595745 (-5200 3375);
PAINT GREEN (-5200 3375);
DISPLAY INVISIBLE (-5200 3375);
FORCEPROP 1 LAST PATH I63
J 0
(-5527 3500);
DISPLAY 0.872340 (-5527 3500);
PAINT GREEN (-5527 3500);
DISPLAY INVISIBLE (-5527 3500);
FORCEADD TAP..6
(-5525 3600);
FORCEPROP 3 LASTPIN (-5475 3600) SIG_NAME M_B_DQ<42>
J 0
(-5465 3610);
DISPLAY 0.659574 (-5465 3610);
PAINT MONO (-5465 3610);
DISPLAY INVISIBLE (-5465 3610);
FORCEPROP 1 LASTPIN (-5475 3600) BN 42
J 0
(-5527 3608);
DISPLAY 0.617021 (-5527 3608);
PAINT PINK (-5527 3608);
FORCEPROP 2 LAST CDS_LIB mstr_standard
J 0
(-5525 3600);
PAINT MONO (-5525 3600);
DISPLAY INVISIBLE (-5525 3600);
FORCEPROP 1 LAST BODY_TYPE PLUMBING
J 0
(-5525 3550);
DISPLAY 1.595745 (-5525 3550);
PAINT GREEN (-5525 3550);
DISPLAY INVISIBLE (-5525 3550);
FORCEPROP 1 LAST HDL_TAP TRUE
J 0
(-5200 3475);
DISPLAY 1.595745 (-5200 3475);
PAINT GREEN (-5200 3475);
DISPLAY INVISIBLE (-5200 3475);
FORCEPROP 1 LAST PATH I64
J 0
(-5527 3600);
DISPLAY 0.872340 (-5527 3600);
PAINT GREEN (-5527 3600);
DISPLAY INVISIBLE (-5527 3600);
FORCEADD TAP..6
(-5525 3650);
FORCEPROP 3 LASTPIN (-5475 3650) SIG_NAME M_B_DQ<43>
J 0
(-5465 3660);
DISPLAY 0.659574 (-5465 3660);
PAINT MONO (-5465 3660);
DISPLAY INVISIBLE (-5465 3660);
FORCEPROP 1 LASTPIN (-5475 3650) BN 43
J 0
(-5527 3658);
DISPLAY 0.617021 (-5527 3658);
PAINT PINK (-5527 3658);
FORCEPROP 2 LAST CDS_LIB mstr_standard
J 0
(-5525 3650);
PAINT MONO (-5525 3650);
DISPLAY INVISIBLE (-5525 3650);
FORCEPROP 1 LAST BODY_TYPE PLUMBING
J 0
(-5525 3600);
DISPLAY 1.595745 (-5525 3600);
PAINT GREEN (-5525 3600);
DISPLAY INVISIBLE (-5525 3600);
FORCEPROP 1 LAST HDL_TAP TRUE
J 0
(-5200 3525);
DISPLAY 1.595745 (-5200 3525);
PAINT GREEN (-5200 3525);
DISPLAY INVISIBLE (-5200 3525);
FORCEPROP 1 LAST PATH I65
J 0
(-5527 3650);
DISPLAY 0.872340 (-5527 3650);
PAINT GREEN (-5527 3650);
DISPLAY INVISIBLE (-5527 3650);
FORCEADD TAP..6
(-5525 3700);
FORCEPROP 3 LASTPIN (-5475 3700) SIG_NAME M_B_DQ<44>
J 0
(-5465 3710);
DISPLAY 0.659574 (-5465 3710);
PAINT MONO (-5465 3710);
DISPLAY INVISIBLE (-5465 3710);
FORCEPROP 1 LASTPIN (-5475 3700) BN 44
J 0
(-5527 3708);
DISPLAY 0.617021 (-5527 3708);
PAINT PINK (-5527 3708);
FORCEPROP 2 LAST CDS_LIB mstr_standard
J 0
(-5525 3700);
PAINT MONO (-5525 3700);
DISPLAY INVISIBLE (-5525 3700);
FORCEPROP 1 LAST BODY_TYPE PLUMBING
J 0
(-5525 3650);
DISPLAY 1.595745 (-5525 3650);
PAINT GREEN (-5525 3650);
DISPLAY INVISIBLE (-5525 3650);
FORCEPROP 1 LAST HDL_TAP TRUE
J 0
(-5200 3575);
DISPLAY 1.595745 (-5200 3575);
PAINT GREEN (-5200 3575);
DISPLAY INVISIBLE (-5200 3575);
FORCEPROP 1 LAST PATH I66
J 0
(-5527 3700);
DISPLAY 0.872340 (-5527 3700);
PAINT GREEN (-5527 3700);
DISPLAY INVISIBLE (-5527 3700);
FORCEADD TAP..6
(-5525 3750);
FORCEPROP 3 LASTPIN (-5475 3750) SIG_NAME M_B_DQ<45>
J 0
(-5465 3760);
DISPLAY 0.659574 (-5465 3760);
PAINT MONO (-5465 3760);
DISPLAY INVISIBLE (-5465 3760);
FORCEPROP 1 LASTPIN (-5475 3750) BN 45
J 0
(-5527 3758);
DISPLAY 0.617021 (-5527 3758);
PAINT PINK (-5527 3758);
FORCEPROP 2 LAST CDS_LIB mstr_standard
J 0
(-5525 3750);
PAINT MONO (-5525 3750);
DISPLAY INVISIBLE (-5525 3750);
FORCEPROP 1 LAST BODY_TYPE PLUMBING
J 0
(-5525 3700);
DISPLAY 1.595745 (-5525 3700);
PAINT GREEN (-5525 3700);
DISPLAY INVISIBLE (-5525 3700);
FORCEPROP 1 LAST HDL_TAP TRUE
J 0
(-5200 3625);
DISPLAY 1.595745 (-5200 3625);
PAINT GREEN (-5200 3625);
DISPLAY INVISIBLE (-5200 3625);
FORCEPROP 1 LAST PATH I67
J 0
(-5527 3750);
DISPLAY 0.872340 (-5527 3750);
PAINT GREEN (-5527 3750);
DISPLAY INVISIBLE (-5527 3750);
FORCEADD TAP..6
(-5525 3800);
FORCEPROP 3 LASTPIN (-5475 3800) SIG_NAME M_B_DQ<46>
J 0
(-5465 3810);
DISPLAY 0.659574 (-5465 3810);
PAINT MONO (-5465 3810);
DISPLAY INVISIBLE (-5465 3810);
FORCEPROP 1 LASTPIN (-5475 3800) BN 46
J 0
(-5527 3808);
DISPLAY 0.617021 (-5527 3808);
PAINT PINK (-5527 3808);
FORCEPROP 2 LAST CDS_LIB mstr_standard
J 0
(-5525 3800);
PAINT MONO (-5525 3800);
DISPLAY INVISIBLE (-5525 3800);
FORCEPROP 1 LAST BODY_TYPE PLUMBING
J 0
(-5525 3750);
DISPLAY 1.595745 (-5525 3750);
PAINT GREEN (-5525 3750);
DISPLAY INVISIBLE (-5525 3750);
FORCEPROP 1 LAST HDL_TAP TRUE
J 0
(-5200 3675);
DISPLAY 1.595745 (-5200 3675);
PAINT GREEN (-5200 3675);
DISPLAY INVISIBLE (-5200 3675);
FORCEPROP 1 LAST PATH I68
J 0
(-5527 3800);
DISPLAY 0.872340 (-5527 3800);
PAINT GREEN (-5527 3800);
DISPLAY INVISIBLE (-5527 3800);
FORCEADD TAP..6
(-5525 3850);
FORCEPROP 3 LASTPIN (-5475 3850) SIG_NAME M_B_DQ<47>
J 0
(-5465 3860);
DISPLAY 0.659574 (-5465 3860);
PAINT MONO (-5465 3860);
DISPLAY INVISIBLE (-5465 3860);
FORCEPROP 1 LASTPIN (-5475 3850) BN 47
J 0
(-5527 3858);
DISPLAY 0.617021 (-5527 3858);
PAINT PINK (-5527 3858);
FORCEPROP 2 LAST CDS_LIB mstr_standard
J 0
(-5525 3850);
PAINT MONO (-5525 3850);
DISPLAY INVISIBLE (-5525 3850);
FORCEPROP 1 LAST BODY_TYPE PLUMBING
J 0
(-5525 3800);
DISPLAY 1.595745 (-5525 3800);
PAINT GREEN (-5525 3800);
DISPLAY INVISIBLE (-5525 3800);
FORCEPROP 1 LAST HDL_TAP TRUE
J 0
(-5200 3725);
DISPLAY 1.595745 (-5200 3725);
PAINT GREEN (-5200 3725);
DISPLAY INVISIBLE (-5200 3725);
FORCEPROP 1 LAST PATH I69
J 0
(-5527 3850);
DISPLAY 0.872340 (-5527 3850);
PAINT GREEN (-5527 3850);
DISPLAY INVISIBLE (-5527 3850);
FORCEADD TAP..6
(-5525 700);
FORCEPROP 3 LASTPIN (-5475 700) SIG_NAME M_B_CLK_DN<2>
J 0
(-5465 710);
DISPLAY 0.659574 (-5465 710);
PAINT MONO (-5465 710);
DISPLAY INVISIBLE (-5465 710);
FORCEPROP 1 LASTPIN (-5475 700) BN 2
J 0
(-5527 708);
DISPLAY 0.617021 (-5527 708);
PAINT PINK (-5527 708);
FORCEPROP 2 LAST CDS_LIB mstr_standard
J 0
(-5525 700);
PAINT MONO (-5525 700);
DISPLAY INVISIBLE (-5525 700);
FORCEPROP 1 LAST BODY_TYPE PLUMBING
J 0
(-5525 650);
DISPLAY 1.595745 (-5525 650);
PAINT GREEN (-5525 650);
DISPLAY INVISIBLE (-5525 650);
FORCEPROP 1 LAST HDL_TAP TRUE
J 0
(-5200 575);
DISPLAY 1.595745 (-5200 575);
PAINT GREEN (-5200 575);
DISPLAY INVISIBLE (-5200 575);
FORCEPROP 1 LAST PATH I7
J 0
(-5527 700);
DISPLAY 0.872340 (-5527 700);
PAINT GREEN (-5527 700);
DISPLAY INVISIBLE (-5527 700);
FORCEADD TAP..6
(-5525 3900);
FORCEPROP 3 LASTPIN (-5475 3900) SIG_NAME M_B_DQ<48>
J 0
(-5465 3910);
DISPLAY 0.659574 (-5465 3910);
PAINT MONO (-5465 3910);
DISPLAY INVISIBLE (-5465 3910);
FORCEPROP 1 LASTPIN (-5475 3900) BN 48
J 0
(-5527 3908);
DISPLAY 0.617021 (-5527 3908);
PAINT PINK (-5527 3908);
FORCEPROP 2 LAST CDS_LIB mstr_standard
J 0
(-5525 3900);
PAINT MONO (-5525 3900);
DISPLAY INVISIBLE (-5525 3900);
FORCEPROP 1 LAST BODY_TYPE PLUMBING
J 0
(-5525 3850);
DISPLAY 1.595745 (-5525 3850);
PAINT GREEN (-5525 3850);
DISPLAY INVISIBLE (-5525 3850);
FORCEPROP 1 LAST HDL_TAP TRUE
J 0
(-5200 3775);
DISPLAY 1.595745 (-5200 3775);
PAINT GREEN (-5200 3775);
DISPLAY INVISIBLE (-5200 3775);
FORCEPROP 1 LAST PATH I70
J 0
(-5527 3900);
DISPLAY 0.872340 (-5527 3900);
PAINT GREEN (-5527 3900);
DISPLAY INVISIBLE (-5527 3900);
FORCEADD TAP..6
(-5525 3950);
FORCEPROP 3 LASTPIN (-5475 3950) SIG_NAME M_B_DQ<49>
J 0
(-5465 3960);
DISPLAY 0.659574 (-5465 3960);
PAINT MONO (-5465 3960);
DISPLAY INVISIBLE (-5465 3960);
FORCEPROP 1 LASTPIN (-5475 3950) BN 49
J 0
(-5527 3958);
DISPLAY 0.617021 (-5527 3958);
PAINT PINK (-5527 3958);
FORCEPROP 2 LAST CDS_LIB mstr_standard
J 0
(-5525 3950);
PAINT MONO (-5525 3950);
DISPLAY INVISIBLE (-5525 3950);
FORCEPROP 1 LAST BODY_TYPE PLUMBING
J 0
(-5525 3900);
DISPLAY 1.595745 (-5525 3900);
PAINT GREEN (-5525 3900);
DISPLAY INVISIBLE (-5525 3900);
FORCEPROP 1 LAST HDL_TAP TRUE
J 0
(-5200 3825);
DISPLAY 1.595745 (-5200 3825);
PAINT GREEN (-5200 3825);
DISPLAY INVISIBLE (-5200 3825);
FORCEPROP 1 LAST PATH I71
J 0
(-5527 3950);
DISPLAY 0.872340 (-5527 3950);
PAINT GREEN (-5527 3950);
DISPLAY INVISIBLE (-5527 3950);
FORCEADD OFFPAGE..6
(-6375 4775);
FORCEPROP 2 LAST $XR0 45 
J 0
(-6654 4775);
DISPLAY 0.638298 (-6654 4775);
PAINT MONO (-6654 4775);
FORCEPROP 2 LAST $XR1 46 
J 0
(-6744 4775);
DISPLAY 0.638298 (-6744 4775);
PAINT MONO (-6744 4775);
FORCEPROP 2 LAST CDS_LIB mstr_standard
J 0
(-6375 4775);
PAINT MONO (-6375 4775);
DISPLAY INVISIBLE (-6375 4775);
FORCEPROP 1 LAST OFFPAGE TRUE
J 0
(-6050 4650);
DISPLAY 1.170213 (-6050 4650);
PAINT GREEN (-6050 4650);
DISPLAY INVISIBLE (-6050 4650);
FORCEPROP 1 LAST COMMENT_BODY TRUE
J 0
(-6275 4700);
DISPLAY 1.170213 (-6275 4700);
PAINT GREEN (-6275 4700);
DISPLAY INVISIBLE (-6275 4700);
FORCEPROP 2 LAST PATH I72
J 0
(-6325 4850);
DISPLAY 1.021277 (-6325 4850);
PAINT ORANGE (-6325 4850);
DISPLAY INVISIBLE (-6325 4850);
FORCEADD TAP..6
(-5525 4050);
FORCEPROP 3 LASTPIN (-5475 4050) SIG_NAME M_B_DQ<51>
J 0
(-5465 4060);
DISPLAY 0.659574 (-5465 4060);
PAINT MONO (-5465 4060);
DISPLAY INVISIBLE (-5465 4060);
FORCEPROP 1 LASTPIN (-5475 4050) BN 51
J 0
(-5527 4058);
DISPLAY 0.617021 (-5527 4058);
PAINT PINK (-5527 4058);
FORCEPROP 2 LAST CDS_LIB mstr_standard
J 0
(-5525 4050);
PAINT MONO (-5525 4050);
DISPLAY INVISIBLE (-5525 4050);
FORCEPROP 1 LAST BODY_TYPE PLUMBING
J 0
(-5525 4000);
DISPLAY 1.595745 (-5525 4000);
PAINT GREEN (-5525 4000);
DISPLAY INVISIBLE (-5525 4000);
FORCEPROP 1 LAST HDL_TAP TRUE
J 0
(-5200 3925);
DISPLAY 1.595745 (-5200 3925);
PAINT GREEN (-5200 3925);
DISPLAY INVISIBLE (-5200 3925);
FORCEPROP 1 LAST PATH I73
J 0
(-5527 4050);
DISPLAY 0.872340 (-5527 4050);
PAINT GREEN (-5527 4050);
DISPLAY INVISIBLE (-5527 4050);
FORCEADD TAP..6
(-5525 4000);
FORCEPROP 3 LASTPIN (-5475 4000) SIG_NAME M_B_DQ<50>
J 0
(-5465 4010);
DISPLAY 0.659574 (-5465 4010);
PAINT MONO (-5465 4010);
DISPLAY INVISIBLE (-5465 4010);
FORCEPROP 1 LASTPIN (-5475 4000) BN 50
J 0
(-5527 4008);
DISPLAY 0.617021 (-5527 4008);
PAINT PINK (-5527 4008);
FORCEPROP 2 LAST CDS_LIB mstr_standard
J 0
(-5525 4000);
PAINT MONO (-5525 4000);
DISPLAY INVISIBLE (-5525 4000);
FORCEPROP 1 LAST BODY_TYPE PLUMBING
J 0
(-5525 3950);
DISPLAY 1.595745 (-5525 3950);
PAINT GREEN (-5525 3950);
DISPLAY INVISIBLE (-5525 3950);
FORCEPROP 1 LAST HDL_TAP TRUE
J 0
(-5200 3875);
DISPLAY 1.595745 (-5200 3875);
PAINT GREEN (-5200 3875);
DISPLAY INVISIBLE (-5200 3875);
FORCEPROP 1 LAST PATH I74
J 0
(-5527 4000);
DISPLAY 0.872340 (-5527 4000);
PAINT GREEN (-5527 4000);
DISPLAY INVISIBLE (-5527 4000);
FORCEADD TAP..6
(-5525 4150);
FORCEPROP 3 LASTPIN (-5475 4150) SIG_NAME M_B_DQ<53>
J 0
(-5465 4160);
DISPLAY 0.659574 (-5465 4160);
PAINT MONO (-5465 4160);
DISPLAY INVISIBLE (-5465 4160);
FORCEPROP 1 LASTPIN (-5475 4150) BN 53
J 0
(-5527 4158);
DISPLAY 0.617021 (-5527 4158);
PAINT PINK (-5527 4158);
FORCEPROP 2 LAST CDS_LIB mstr_standard
J 0
(-5525 4150);
PAINT MONO (-5525 4150);
DISPLAY INVISIBLE (-5525 4150);
FORCEPROP 1 LAST BODY_TYPE PLUMBING
J 0
(-5525 4100);
DISPLAY 1.595745 (-5525 4100);
PAINT GREEN (-5525 4100);
DISPLAY INVISIBLE (-5525 4100);
FORCEPROP 1 LAST HDL_TAP TRUE
J 0
(-5200 4025);
DISPLAY 1.595745 (-5200 4025);
PAINT GREEN (-5200 4025);
DISPLAY INVISIBLE (-5200 4025);
FORCEPROP 1 LAST PATH I75
J 0
(-5527 4150);
DISPLAY 0.872340 (-5527 4150);
PAINT GREEN (-5527 4150);
DISPLAY INVISIBLE (-5527 4150);
FORCEADD TAP..6
(-5525 4200);
FORCEPROP 3 LASTPIN (-5475 4200) SIG_NAME M_B_DQ<54>
J 0
(-5465 4210);
DISPLAY 0.659574 (-5465 4210);
PAINT MONO (-5465 4210);
DISPLAY INVISIBLE (-5465 4210);
FORCEPROP 1 LASTPIN (-5475 4200) BN 54
J 0
(-5527 4208);
DISPLAY 0.617021 (-5527 4208);
PAINT PINK (-5527 4208);
FORCEPROP 2 LAST CDS_LIB mstr_standard
J 0
(-5525 4200);
PAINT MONO (-5525 4200);
DISPLAY INVISIBLE (-5525 4200);
FORCEPROP 1 LAST BODY_TYPE PLUMBING
J 0
(-5525 4150);
DISPLAY 1.595745 (-5525 4150);
PAINT GREEN (-5525 4150);
DISPLAY INVISIBLE (-5525 4150);
FORCEPROP 1 LAST HDL_TAP TRUE
J 0
(-5200 4075);
DISPLAY 1.595745 (-5200 4075);
PAINT GREEN (-5200 4075);
DISPLAY INVISIBLE (-5200 4075);
FORCEPROP 1 LAST PATH I76
J 0
(-5527 4200);
DISPLAY 0.872340 (-5527 4200);
PAINT GREEN (-5527 4200);
DISPLAY INVISIBLE (-5527 4200);
FORCEADD TAP..6
(-5525 4100);
FORCEPROP 3 LASTPIN (-5475 4100) SIG_NAME M_B_DQ<52>
J 0
(-5465 4110);
DISPLAY 0.659574 (-5465 4110);
PAINT MONO (-5465 4110);
DISPLAY INVISIBLE (-5465 4110);
FORCEPROP 1 LASTPIN (-5475 4100) BN 52
J 0
(-5527 4108);
DISPLAY 0.617021 (-5527 4108);
PAINT PINK (-5527 4108);
FORCEPROP 2 LAST CDS_LIB mstr_standard
J 0
(-5525 4100);
PAINT MONO (-5525 4100);
DISPLAY INVISIBLE (-5525 4100);
FORCEPROP 1 LAST BODY_TYPE PLUMBING
J 0
(-5525 4050);
DISPLAY 1.595745 (-5525 4050);
PAINT GREEN (-5525 4050);
DISPLAY INVISIBLE (-5525 4050);
FORCEPROP 1 LAST HDL_TAP TRUE
J 0
(-5200 3975);
DISPLAY 1.595745 (-5200 3975);
PAINT GREEN (-5200 3975);
DISPLAY INVISIBLE (-5200 3975);
FORCEPROP 1 LAST PATH I77
J 0
(-5527 4100);
DISPLAY 0.872340 (-5527 4100);
PAINT GREEN (-5527 4100);
DISPLAY INVISIBLE (-5527 4100);
FORCEADD TAP..6
(-5525 4250);
FORCEPROP 3 LASTPIN (-5475 4250) SIG_NAME M_B_DQ<55>
J 0
(-5465 4260);
DISPLAY 0.659574 (-5465 4260);
PAINT MONO (-5465 4260);
DISPLAY INVISIBLE (-5465 4260);
FORCEPROP 1 LASTPIN (-5475 4250) BN 55
J 0
(-5527 4258);
DISPLAY 0.617021 (-5527 4258);
PAINT PINK (-5527 4258);
FORCEPROP 2 LAST CDS_LIB mstr_standard
J 0
(-5525 4250);
PAINT MONO (-5525 4250);
DISPLAY INVISIBLE (-5525 4250);
FORCEPROP 1 LAST BODY_TYPE PLUMBING
J 0
(-5525 4200);
DISPLAY 1.595745 (-5525 4200);
PAINT GREEN (-5525 4200);
DISPLAY INVISIBLE (-5525 4200);
FORCEPROP 1 LAST HDL_TAP TRUE
J 0
(-5200 4125);
DISPLAY 1.595745 (-5200 4125);
PAINT GREEN (-5200 4125);
DISPLAY INVISIBLE (-5200 4125);
FORCEPROP 1 LAST PATH I78
J 0
(-5527 4250);
DISPLAY 0.872340 (-5527 4250);
PAINT GREEN (-5527 4250);
DISPLAY INVISIBLE (-5527 4250);
FORCEADD TAP..6
(-5525 4300);
FORCEPROP 3 LASTPIN (-5475 4300) SIG_NAME M_B_DQ<56>
J 0
(-5465 4310);
DISPLAY 0.659574 (-5465 4310);
PAINT MONO (-5465 4310);
DISPLAY INVISIBLE (-5465 4310);
FORCEPROP 1 LASTPIN (-5475 4300) BN 56
J 0
(-5527 4308);
DISPLAY 0.617021 (-5527 4308);
PAINT PINK (-5527 4308);
FORCEPROP 2 LAST CDS_LIB mstr_standard
J 0
(-5525 4300);
PAINT MONO (-5525 4300);
DISPLAY INVISIBLE (-5525 4300);
FORCEPROP 1 LAST BODY_TYPE PLUMBING
J 0
(-5525 4250);
DISPLAY 1.595745 (-5525 4250);
PAINT GREEN (-5525 4250);
DISPLAY INVISIBLE (-5525 4250);
FORCEPROP 1 LAST HDL_TAP TRUE
J 0
(-5200 4175);
DISPLAY 1.595745 (-5200 4175);
PAINT GREEN (-5200 4175);
DISPLAY INVISIBLE (-5200 4175);
FORCEPROP 1 LAST PATH I79
J 0
(-5527 4300);
DISPLAY 0.872340 (-5527 4300);
PAINT GREEN (-5527 4300);
DISPLAY INVISIBLE (-5527 4300);
FORCEADD TAP..6
(-5525 800);
FORCEPROP 3 LASTPIN (-5475 800) SIG_NAME M_B_CLK_DP<0>
J 0
(-5465 810);
DISPLAY 0.659574 (-5465 810);
PAINT MONO (-5465 810);
DISPLAY INVISIBLE (-5465 810);
FORCEPROP 1 LASTPIN (-5475 800) BN 0
J 0
(-5527 808);
DISPLAY 0.617021 (-5527 808);
PAINT PINK (-5527 808);
FORCEPROP 2 LAST CDS_LIB mstr_standard
J 0
(-5525 800);
PAINT MONO (-5525 800);
DISPLAY INVISIBLE (-5525 800);
FORCEPROP 1 LAST BODY_TYPE PLUMBING
J 0
(-5525 750);
DISPLAY 1.595745 (-5525 750);
PAINT GREEN (-5525 750);
DISPLAY INVISIBLE (-5525 750);
FORCEPROP 1 LAST HDL_TAP TRUE
J 0
(-5200 675);
DISPLAY 1.595745 (-5200 675);
PAINT GREEN (-5200 675);
DISPLAY INVISIBLE (-5200 675);
FORCEPROP 1 LAST PATH I8
J 0
(-5527 800);
DISPLAY 0.872340 (-5527 800);
PAINT GREEN (-5527 800);
DISPLAY INVISIBLE (-5527 800);
FORCEADD TAP..6
(-5525 4350);
FORCEPROP 3 LASTPIN (-5475 4350) SIG_NAME M_B_DQ<57>
J 0
(-5465 4360);
DISPLAY 0.659574 (-5465 4360);
PAINT MONO (-5465 4360);
DISPLAY INVISIBLE (-5465 4360);
FORCEPROP 1 LASTPIN (-5475 4350) BN 57
J 0
(-5527 4358);
DISPLAY 0.617021 (-5527 4358);
PAINT PINK (-5527 4358);
FORCEPROP 2 LAST CDS_LIB mstr_standard
J 0
(-5525 4350);
PAINT MONO (-5525 4350);
DISPLAY INVISIBLE (-5525 4350);
FORCEPROP 1 LAST BODY_TYPE PLUMBING
J 0
(-5525 4300);
DISPLAY 1.595745 (-5525 4300);
PAINT GREEN (-5525 4300);
DISPLAY INVISIBLE (-5525 4300);
FORCEPROP 1 LAST HDL_TAP TRUE
J 0
(-5200 4225);
DISPLAY 1.595745 (-5200 4225);
PAINT GREEN (-5200 4225);
DISPLAY INVISIBLE (-5200 4225);
FORCEPROP 1 LAST PATH I80
J 0
(-5527 4350);
DISPLAY 0.872340 (-5527 4350);
PAINT GREEN (-5527 4350);
DISPLAY INVISIBLE (-5527 4350);
FORCEADD TAP..6
(-5525 4400);
FORCEPROP 3 LASTPIN (-5475 4400) SIG_NAME M_B_DQ<58>
J 0
(-5465 4410);
DISPLAY 0.659574 (-5465 4410);
PAINT MONO (-5465 4410);
DISPLAY INVISIBLE (-5465 4410);
FORCEPROP 1 LASTPIN (-5475 4400) BN 58
J 0
(-5527 4408);
DISPLAY 0.617021 (-5527 4408);
PAINT PINK (-5527 4408);
FORCEPROP 2 LAST CDS_LIB mstr_standard
J 0
(-5525 4400);
PAINT MONO (-5525 4400);
DISPLAY INVISIBLE (-5525 4400);
FORCEPROP 1 LAST BODY_TYPE PLUMBING
J 0
(-5525 4350);
DISPLAY 1.595745 (-5525 4350);
PAINT GREEN (-5525 4350);
DISPLAY INVISIBLE (-5525 4350);
FORCEPROP 1 LAST HDL_TAP TRUE
J 0
(-5200 4275);
DISPLAY 1.595745 (-5200 4275);
PAINT GREEN (-5200 4275);
DISPLAY INVISIBLE (-5200 4275);
FORCEPROP 1 LAST PATH I81
J 0
(-5527 4400);
DISPLAY 0.872340 (-5527 4400);
PAINT GREEN (-5527 4400);
DISPLAY INVISIBLE (-5527 4400);
FORCEADD TAP..6
(-5525 4450);
FORCEPROP 3 LASTPIN (-5475 4450) SIG_NAME M_B_DQ<59>
J 0
(-5465 4460);
DISPLAY 0.659574 (-5465 4460);
PAINT MONO (-5465 4460);
DISPLAY INVISIBLE (-5465 4460);
FORCEPROP 1 LASTPIN (-5475 4450) BN 59
J 0
(-5527 4458);
DISPLAY 0.617021 (-5527 4458);
PAINT PINK (-5527 4458);
FORCEPROP 2 LAST CDS_LIB mstr_standard
J 0
(-5525 4450);
PAINT MONO (-5525 4450);
DISPLAY INVISIBLE (-5525 4450);
FORCEPROP 1 LAST BODY_TYPE PLUMBING
J 0
(-5525 4400);
DISPLAY 1.595745 (-5525 4400);
PAINT GREEN (-5525 4400);
DISPLAY INVISIBLE (-5525 4400);
FORCEPROP 1 LAST HDL_TAP TRUE
J 0
(-5200 4325);
DISPLAY 1.595745 (-5200 4325);
PAINT GREEN (-5200 4325);
DISPLAY INVISIBLE (-5200 4325);
FORCEPROP 1 LAST PATH I82
J 0
(-5527 4450);
DISPLAY 0.872340 (-5527 4450);
PAINT GREEN (-5527 4450);
DISPLAY INVISIBLE (-5527 4450);
FORCEADD TAP..6
(-5525 4500);
FORCEPROP 3 LASTPIN (-5475 4500) SIG_NAME M_B_DQ<60>
J 0
(-5465 4510);
DISPLAY 0.659574 (-5465 4510);
PAINT MONO (-5465 4510);
DISPLAY INVISIBLE (-5465 4510);
FORCEPROP 1 LASTPIN (-5475 4500) BN 60
J 0
(-5527 4508);
DISPLAY 0.617021 (-5527 4508);
PAINT PINK (-5527 4508);
FORCEPROP 2 LAST CDS_LIB mstr_standard
J 0
(-5525 4500);
PAINT MONO (-5525 4500);
DISPLAY INVISIBLE (-5525 4500);
FORCEPROP 1 LAST BODY_TYPE PLUMBING
J 0
(-5525 4450);
DISPLAY 1.595745 (-5525 4450);
PAINT GREEN (-5525 4450);
DISPLAY INVISIBLE (-5525 4450);
FORCEPROP 1 LAST HDL_TAP TRUE
J 0
(-5200 4375);
DISPLAY 1.595745 (-5200 4375);
PAINT GREEN (-5200 4375);
DISPLAY INVISIBLE (-5200 4375);
FORCEPROP 1 LAST PATH I83
J 0
(-5527 4500);
DISPLAY 0.872340 (-5527 4500);
PAINT GREEN (-5527 4500);
DISPLAY INVISIBLE (-5527 4500);
FORCEADD TAP..6
(-5525 4550);
FORCEPROP 3 LASTPIN (-5475 4550) SIG_NAME M_B_DQ<61>
J 0
(-5465 4560);
DISPLAY 0.659574 (-5465 4560);
PAINT MONO (-5465 4560);
DISPLAY INVISIBLE (-5465 4560);
FORCEPROP 1 LASTPIN (-5475 4550) BN 61
J 0
(-5527 4558);
DISPLAY 0.617021 (-5527 4558);
PAINT PINK (-5527 4558);
FORCEPROP 2 LAST CDS_LIB mstr_standard
J 0
(-5525 4550);
PAINT MONO (-5525 4550);
DISPLAY INVISIBLE (-5525 4550);
FORCEPROP 1 LAST BODY_TYPE PLUMBING
J 0
(-5525 4500);
DISPLAY 1.595745 (-5525 4500);
PAINT GREEN (-5525 4500);
DISPLAY INVISIBLE (-5525 4500);
FORCEPROP 1 LAST HDL_TAP TRUE
J 0
(-5200 4425);
DISPLAY 1.595745 (-5200 4425);
PAINT GREEN (-5200 4425);
DISPLAY INVISIBLE (-5200 4425);
FORCEPROP 1 LAST PATH I84
J 0
(-5527 4550);
DISPLAY 0.872340 (-5527 4550);
PAINT GREEN (-5527 4550);
DISPLAY INVISIBLE (-5527 4550);
FORCEADD TAP..6
(-5525 4650);
FORCEPROP 3 LASTPIN (-5475 4650) SIG_NAME M_B_DQ<63>
J 0
(-5465 4660);
DISPLAY 0.659574 (-5465 4660);
PAINT MONO (-5465 4660);
DISPLAY INVISIBLE (-5465 4660);
FORCEPROP 1 LASTPIN (-5475 4650) BN 63
J 0
(-5527 4658);
DISPLAY 0.617021 (-5527 4658);
PAINT PINK (-5527 4658);
FORCEPROP 2 LAST CDS_LIB mstr_standard
J 0
(-5525 4650);
PAINT MONO (-5525 4650);
DISPLAY INVISIBLE (-5525 4650);
FORCEPROP 1 LAST BODY_TYPE PLUMBING
J 0
(-5525 4600);
DISPLAY 1.595745 (-5525 4600);
PAINT GREEN (-5525 4600);
DISPLAY INVISIBLE (-5525 4600);
FORCEPROP 1 LAST HDL_TAP TRUE
J 0
(-5200 4525);
DISPLAY 1.595745 (-5200 4525);
PAINT GREEN (-5200 4525);
DISPLAY INVISIBLE (-5200 4525);
FORCEPROP 1 LAST PATH I85
J 0
(-5527 4650);
DISPLAY 0.872340 (-5527 4650);
PAINT GREEN (-5527 4650);
DISPLAY INVISIBLE (-5527 4650);
FORCEADD TAP..6
(-5525 4600);
FORCEPROP 3 LASTPIN (-5475 4600) SIG_NAME M_B_DQ<62>
J 0
(-5465 4610);
DISPLAY 0.659574 (-5465 4610);
PAINT MONO (-5465 4610);
DISPLAY INVISIBLE (-5465 4610);
FORCEPROP 1 LASTPIN (-5475 4600) BN 62
J 0
(-5527 4608);
DISPLAY 0.617021 (-5527 4608);
PAINT PINK (-5527 4608);
FORCEPROP 2 LAST CDS_LIB mstr_standard
J 0
(-5525 4600);
PAINT MONO (-5525 4600);
DISPLAY INVISIBLE (-5525 4600);
FORCEPROP 1 LAST BODY_TYPE PLUMBING
J 0
(-5525 4550);
DISPLAY 1.595745 (-5525 4550);
PAINT GREEN (-5525 4550);
DISPLAY INVISIBLE (-5525 4550);
FORCEPROP 1 LAST HDL_TAP TRUE
J 0
(-5200 4475);
DISPLAY 1.595745 (-5200 4475);
PAINT GREEN (-5200 4475);
DISPLAY INVISIBLE (-5200 4475);
FORCEPROP 1 LAST PATH I86
J 0
(-5527 4600);
DISPLAY 0.872340 (-5527 4600);
PAINT GREEN (-5527 4600);
DISPLAY INVISIBLE (-5527 4600);
FORCEADD TAP..6
R 2
(-2800 800);
FORCEPROP 3 LASTPIN (-2850 800) SIG_NAME M_B_BG<0>
J 0
(-2840 810);
DISPLAY 0.659574 (-2840 810);
PAINT MONO (-2840 810);
DISPLAY INVISIBLE (-2840 810);
FORCEPROP 1 LASTPIN (-2850 800) BN 0
J 2
(-2798 808);
DISPLAY 0.617021 (-2798 808);
PAINT PINK (-2798 808);
FORCEPROP 2 LAST CDS_LIB mstr_standard
J 0
(-2800 800);
PAINT MONO (-2800 800);
DISPLAY INVISIBLE (-2800 800);
FORCEPROP 1 LAST BODY_TYPE PLUMBING
J 2
(-2800 750);
DISPLAY 1.595745 (-2800 750);
PAINT GREEN (-2800 750);
DISPLAY INVISIBLE (-2800 750);
FORCEPROP 1 LAST HDL_TAP TRUE
J 2
(-3125 675);
DISPLAY 1.595745 (-3125 675);
PAINT GREEN (-3125 675);
DISPLAY INVISIBLE (-3125 675);
FORCEPROP 1 LAST PATH I87
J 2
(-2798 800);
DISPLAY 0.872340 (-2798 800);
PAINT GREEN (-2798 800);
DISPLAY INVISIBLE (-2798 800);
FORCEADD TAP..6
R 2
(-2800 850);
FORCEPROP 3 LASTPIN (-2850 850) SIG_NAME M_B_BG<1>
J 0
(-2840 860);
DISPLAY 0.659574 (-2840 860);
PAINT MONO (-2840 860);
DISPLAY INVISIBLE (-2840 860);
FORCEPROP 1 LASTPIN (-2850 850) BN 1
J 2
(-2798 858);
DISPLAY 0.617021 (-2798 858);
PAINT PINK (-2798 858);
FORCEPROP 2 LAST CDS_LIB mstr_standard
J 0
(-2800 850);
PAINT MONO (-2800 850);
DISPLAY INVISIBLE (-2800 850);
FORCEPROP 1 LAST BODY_TYPE PLUMBING
J 2
(-2800 800);
DISPLAY 1.595745 (-2800 800);
PAINT GREEN (-2800 800);
DISPLAY INVISIBLE (-2800 800);
FORCEPROP 1 LAST HDL_TAP TRUE
J 2
(-3125 725);
DISPLAY 1.595745 (-3125 725);
PAINT GREEN (-3125 725);
DISPLAY INVISIBLE (-3125 725);
FORCEPROP 1 LAST PATH I88
J 2
(-2798 850);
DISPLAY 0.872340 (-2798 850);
PAINT GREEN (-2798 850);
DISPLAY INVISIBLE (-2798 850);
FORCEADD TAP..6
R 2
(-2800 750);
FORCEPROP 3 LASTPIN (-2850 750) SIG_NAME M_B_BA<1>
J 0
(-2840 760);
DISPLAY 0.659574 (-2840 760);
PAINT MONO (-2840 760);
DISPLAY INVISIBLE (-2840 760);
FORCEPROP 1 LASTPIN (-2850 750) BN 1
J 2
(-2798 758);
DISPLAY 0.617021 (-2798 758);
PAINT PINK (-2798 758);
FORCEPROP 2 LAST CDS_LIB mstr_standard
J 0
(-2800 750);
PAINT MONO (-2800 750);
DISPLAY INVISIBLE (-2800 750);
FORCEPROP 1 LAST BODY_TYPE PLUMBING
J 2
(-2800 700);
DISPLAY 1.595745 (-2800 700);
PAINT GREEN (-2800 700);
DISPLAY INVISIBLE (-2800 700);
FORCEPROP 1 LAST HDL_TAP TRUE
J 2
(-3125 625);
DISPLAY 1.595745 (-3125 625);
PAINT GREEN (-3125 625);
DISPLAY INVISIBLE (-3125 625);
FORCEPROP 1 LAST PATH I89
J 2
(-2798 750);
DISPLAY 0.872340 (-2798 750);
PAINT GREEN (-2798 750);
DISPLAY INVISIBLE (-2798 750);
FORCEADD TAP..6
(-5525 850);
FORCEPROP 3 LASTPIN (-5475 850) SIG_NAME M_B_CLK_DP<1>
J 0
(-5465 860);
DISPLAY 0.659574 (-5465 860);
PAINT MONO (-5465 860);
DISPLAY INVISIBLE (-5465 860);
FORCEPROP 1 LASTPIN (-5475 850) BN 1
J 0
(-5527 858);
DISPLAY 0.617021 (-5527 858);
PAINT PINK (-5527 858);
FORCEPROP 2 LAST CDS_LIB mstr_standard
J 0
(-5525 850);
PAINT MONO (-5525 850);
DISPLAY INVISIBLE (-5525 850);
FORCEPROP 1 LAST BODY_TYPE PLUMBING
J 0
(-5525 800);
DISPLAY 1.595745 (-5525 800);
PAINT GREEN (-5525 800);
DISPLAY INVISIBLE (-5525 800);
FORCEPROP 1 LAST HDL_TAP TRUE
J 0
(-5200 725);
DISPLAY 1.595745 (-5200 725);
PAINT GREEN (-5200 725);
DISPLAY INVISIBLE (-5200 725);
FORCEPROP 1 LAST PATH I9
J 0
(-5527 850);
DISPLAY 0.872340 (-5527 850);
PAINT GREEN (-5527 850);
DISPLAY INVISIBLE (-5527 850);
FORCEADD TAP..6
R 2
(-2800 700);
FORCEPROP 3 LASTPIN (-2850 700) SIG_NAME M_B_BA<0>
J 0
(-2840 710);
DISPLAY 0.659574 (-2840 710);
PAINT MONO (-2840 710);
DISPLAY INVISIBLE (-2840 710);
FORCEPROP 1 LASTPIN (-2850 700) BN 0
J 2
(-2798 708);
DISPLAY 0.617021 (-2798 708);
PAINT PINK (-2798 708);
FORCEPROP 2 LAST CDS_LIB mstr_standard
J 0
(-2800 700);
PAINT MONO (-2800 700);
DISPLAY INVISIBLE (-2800 700);
FORCEPROP 1 LAST BODY_TYPE PLUMBING
J 2
(-2800 650);
DISPLAY 1.595745 (-2800 650);
PAINT GREEN (-2800 650);
DISPLAY INVISIBLE (-2800 650);
FORCEPROP 1 LAST HDL_TAP TRUE
J 2
(-3125 575);
DISPLAY 1.595745 (-3125 575);
PAINT GREEN (-3125 575);
DISPLAY INVISIBLE (-3125 575);
FORCEPROP 1 LAST PATH I90
J 2
(-2798 700);
DISPLAY 0.872340 (-2798 700);
PAINT GREEN (-2798 700);
DISPLAY INVISIBLE (-2798 700);
FORCEADD TAP..6
R 2
(-2800 950);
FORCEPROP 3 LASTPIN (-2850 950) SIG_NAME M_B_CS_N<0>
J 0
(-2840 960);
DISPLAY 0.659574 (-2840 960);
PAINT MONO (-2840 960);
DISPLAY INVISIBLE (-2840 960);
FORCEPROP 1 LASTPIN (-2850 950) BN 0
J 2
(-2798 958);
DISPLAY 0.617021 (-2798 958);
PAINT PINK (-2798 958);
FORCEPROP 2 LAST CDS_LIB mstr_standard
J 0
(-2800 950);
PAINT MONO (-2800 950);
DISPLAY INVISIBLE (-2800 950);
FORCEPROP 1 LAST BODY_TYPE PLUMBING
J 2
(-2800 900);
DISPLAY 1.595745 (-2800 900);
PAINT GREEN (-2800 900);
DISPLAY INVISIBLE (-2800 900);
FORCEPROP 1 LAST HDL_TAP TRUE
J 2
(-3125 825);
DISPLAY 1.595745 (-3125 825);
PAINT GREEN (-3125 825);
DISPLAY INVISIBLE (-3125 825);
FORCEPROP 1 LAST PATH I91
J 2
(-2798 950);
DISPLAY 0.872340 (-2798 950);
PAINT GREEN (-2798 950);
DISPLAY INVISIBLE (-2798 950);
FORCEADD TAP..6
R 2
(-2800 1150);
FORCEPROP 3 LASTPIN (-2850 1150) SIG_NAME M_B_CS_N<4>
J 0
(-2840 1160);
DISPLAY 0.659574 (-2840 1160);
PAINT MONO (-2840 1160);
DISPLAY INVISIBLE (-2840 1160);
FORCEPROP 1 LASTPIN (-2850 1150) BN 4
J 2
(-2798 1158);
DISPLAY 0.617021 (-2798 1158);
PAINT PINK (-2798 1158);
FORCEPROP 2 LAST CDS_LIB mstr_standard
J 0
(-2800 1150);
PAINT MONO (-2800 1150);
DISPLAY INVISIBLE (-2800 1150);
FORCEPROP 1 LAST BODY_TYPE PLUMBING
J 2
(-2800 1100);
DISPLAY 1.595745 (-2800 1100);
PAINT GREEN (-2800 1100);
DISPLAY INVISIBLE (-2800 1100);
FORCEPROP 1 LAST HDL_TAP TRUE
J 2
(-3125 1025);
DISPLAY 1.595745 (-3125 1025);
PAINT GREEN (-3125 1025);
DISPLAY INVISIBLE (-3125 1025);
FORCEPROP 1 LAST PATH I92
J 2
(-2798 1150);
DISPLAY 0.872340 (-2798 1150);
PAINT GREEN (-2798 1150);
DISPLAY INVISIBLE (-2798 1150);
FORCEADD TAP..6
R 2
(-2800 1100);
FORCEPROP 3 LASTPIN (-2850 1100) SIG_NAME M_B_CS_N<3>
J 0
(-2840 1110);
DISPLAY 0.659574 (-2840 1110);
PAINT MONO (-2840 1110);
DISPLAY INVISIBLE (-2840 1110);
FORCEPROP 1 LASTPIN (-2850 1100) BN 3
J 2
(-2798 1108);
DISPLAY 0.617021 (-2798 1108);
PAINT PINK (-2798 1108);
FORCEPROP 2 LAST CDS_LIB mstr_standard
J 0
(-2800 1100);
PAINT MONO (-2800 1100);
DISPLAY INVISIBLE (-2800 1100);
FORCEPROP 1 LAST BODY_TYPE PLUMBING
J 2
(-2800 1050);
DISPLAY 1.595745 (-2800 1050);
PAINT GREEN (-2800 1050);
DISPLAY INVISIBLE (-2800 1050);
FORCEPROP 1 LAST HDL_TAP TRUE
J 2
(-3125 975);
DISPLAY 1.595745 (-3125 975);
PAINT GREEN (-3125 975);
DISPLAY INVISIBLE (-3125 975);
FORCEPROP 1 LAST PATH I93
J 2
(-2798 1100);
DISPLAY 0.872340 (-2798 1100);
PAINT GREEN (-2798 1100);
DISPLAY INVISIBLE (-2798 1100);
FORCEADD TAP..6
R 2
(-2800 1050);
FORCEPROP 3 LASTPIN (-2850 1050) SIG_NAME M_B_CS_N<2>
J 0
(-2840 1060);
DISPLAY 0.659574 (-2840 1060);
PAINT MONO (-2840 1060);
DISPLAY INVISIBLE (-2840 1060);
FORCEPROP 1 LASTPIN (-2850 1050) BN 2
J 2
(-2798 1058);
DISPLAY 0.617021 (-2798 1058);
PAINT PINK (-2798 1058);
FORCEPROP 2 LAST CDS_LIB mstr_standard
J 0
(-2800 1050);
PAINT MONO (-2800 1050);
DISPLAY INVISIBLE (-2800 1050);
FORCEPROP 1 LAST BODY_TYPE PLUMBING
J 2
(-2800 1000);
DISPLAY 1.595745 (-2800 1000);
PAINT GREEN (-2800 1000);
DISPLAY INVISIBLE (-2800 1000);
FORCEPROP 1 LAST HDL_TAP TRUE
J 2
(-3125 925);
DISPLAY 1.595745 (-3125 925);
PAINT GREEN (-3125 925);
DISPLAY INVISIBLE (-3125 925);
FORCEPROP 1 LAST PATH I94
J 2
(-2798 1050);
DISPLAY 0.872340 (-2798 1050);
PAINT GREEN (-2798 1050);
DISPLAY INVISIBLE (-2798 1050);
FORCEADD TAP..6
R 2
(-2800 1000);
FORCEPROP 3 LASTPIN (-2850 1000) SIG_NAME M_B_CS_N<1>
J 0
(-2840 1010);
DISPLAY 0.659574 (-2840 1010);
PAINT MONO (-2840 1010);
DISPLAY INVISIBLE (-2840 1010);
FORCEPROP 1 LASTPIN (-2850 1000) BN 1
J 2
(-2798 1008);
DISPLAY 0.617021 (-2798 1008);
PAINT PINK (-2798 1008);
FORCEPROP 2 LAST CDS_LIB mstr_standard
J 0
(-2800 1000);
PAINT MONO (-2800 1000);
DISPLAY INVISIBLE (-2800 1000);
FORCEPROP 1 LAST BODY_TYPE PLUMBING
J 2
(-2800 950);
DISPLAY 1.595745 (-2800 950);
PAINT GREEN (-2800 950);
DISPLAY INVISIBLE (-2800 950);
FORCEPROP 1 LAST HDL_TAP TRUE
J 2
(-3125 875);
DISPLAY 1.595745 (-3125 875);
PAINT GREEN (-3125 875);
DISPLAY INVISIBLE (-3125 875);
FORCEPROP 1 LAST PATH I95
J 2
(-2798 1000);
DISPLAY 0.872340 (-2798 1000);
PAINT GREEN (-2798 1000);
DISPLAY INVISIBLE (-2798 1000);
FORCEADD TAP..6
R 2
(-2800 1400);
FORCEPROP 3 LASTPIN (-2850 1400) SIG_NAME M_B_ODT<0>
J 0
(-2840 1410);
DISPLAY 0.659574 (-2840 1410);
PAINT MONO (-2840 1410);
DISPLAY INVISIBLE (-2840 1410);
FORCEPROP 1 LASTPIN (-2850 1400) BN 0
J 2
(-2798 1408);
DISPLAY 0.617021 (-2798 1408);
PAINT PINK (-2798 1408);
FORCEPROP 2 LAST CDS_LIB mstr_standard
J 0
(-2800 1400);
PAINT MONO (-2800 1400);
DISPLAY INVISIBLE (-2800 1400);
FORCEPROP 1 LAST BODY_TYPE PLUMBING
J 2
(-2800 1350);
DISPLAY 1.595745 (-2800 1350);
PAINT GREEN (-2800 1350);
DISPLAY INVISIBLE (-2800 1350);
FORCEPROP 1 LAST HDL_TAP TRUE
J 2
(-3125 1275);
DISPLAY 1.595745 (-3125 1275);
PAINT GREEN (-3125 1275);
DISPLAY INVISIBLE (-3125 1275);
FORCEPROP 1 LAST PATH I96
J 2
(-2798 1400);
DISPLAY 0.872340 (-2798 1400);
PAINT GREEN (-2798 1400);
DISPLAY INVISIBLE (-2798 1400);
FORCEADD TAP..6
R 2
(-2800 1250);
FORCEPROP 3 LASTPIN (-2850 1250) SIG_NAME M_B_CS_N<6>
J 0
(-2840 1260);
DISPLAY 0.659574 (-2840 1260);
PAINT MONO (-2840 1260);
DISPLAY INVISIBLE (-2840 1260);
FORCEPROP 1 LASTPIN (-2850 1250) BN 6
J 2
(-2798 1258);
DISPLAY 0.617021 (-2798 1258);
PAINT PINK (-2798 1258);
FORCEPROP 2 LAST CDS_LIB mstr_standard
J 0
(-2800 1250);
PAINT MONO (-2800 1250);
DISPLAY INVISIBLE (-2800 1250);
FORCEPROP 1 LAST BODY_TYPE PLUMBING
J 2
(-2800 1200);
DISPLAY 1.595745 (-2800 1200);
PAINT GREEN (-2800 1200);
DISPLAY INVISIBLE (-2800 1200);
FORCEPROP 1 LAST HDL_TAP TRUE
J 2
(-3125 1125);
DISPLAY 1.595745 (-3125 1125);
PAINT GREEN (-3125 1125);
DISPLAY INVISIBLE (-3125 1125);
FORCEPROP 1 LAST PATH I97
J 2
(-2798 1250);
DISPLAY 0.872340 (-2798 1250);
PAINT GREEN (-2798 1250);
DISPLAY INVISIBLE (-2798 1250);
FORCEADD TAP..6
R 2
(-2800 1200);
FORCEPROP 3 LASTPIN (-2850 1200) SIG_NAME M_B_CS_N<5>
J 0
(-2840 1210);
DISPLAY 0.659574 (-2840 1210);
PAINT MONO (-2840 1210);
DISPLAY INVISIBLE (-2840 1210);
FORCEPROP 1 LASTPIN (-2850 1200) BN 5
J 2
(-2798 1208);
DISPLAY 0.617021 (-2798 1208);
PAINT PINK (-2798 1208);
FORCEPROP 2 LAST CDS_LIB mstr_standard
J 0
(-2800 1200);
PAINT MONO (-2800 1200);
DISPLAY INVISIBLE (-2800 1200);
FORCEPROP 1 LAST BODY_TYPE PLUMBING
J 2
(-2800 1150);
DISPLAY 1.595745 (-2800 1150);
PAINT GREEN (-2800 1150);
DISPLAY INVISIBLE (-2800 1150);
FORCEPROP 1 LAST HDL_TAP TRUE
J 2
(-3125 1075);
DISPLAY 1.595745 (-3125 1075);
PAINT GREEN (-3125 1075);
DISPLAY INVISIBLE (-3125 1075);
FORCEPROP 1 LAST PATH I98
J 2
(-2798 1200);
DISPLAY 0.872340 (-2798 1200);
PAINT GREEN (-2798 1200);
DISPLAY INVISIBLE (-2798 1200);
FORCEADD TAP..6
R 2
(-2800 1300);
FORCEPROP 3 LASTPIN (-2850 1300) SIG_NAME M_B_CS_N<7>
J 0
(-2840 1310);
DISPLAY 0.659574 (-2840 1310);
PAINT MONO (-2840 1310);
DISPLAY INVISIBLE (-2840 1310);
FORCEPROP 1 LASTPIN (-2850 1300) BN 7
J 2
(-2798 1308);
DISPLAY 0.617021 (-2798 1308);
PAINT PINK (-2798 1308);
FORCEPROP 2 LAST CDS_LIB mstr_standard
J 0
(-2800 1300);
PAINT MONO (-2800 1300);
DISPLAY INVISIBLE (-2800 1300);
FORCEPROP 1 LAST BODY_TYPE PLUMBING
J 2
(-2800 1250);
DISPLAY 1.595745 (-2800 1250);
PAINT GREEN (-2800 1250);
DISPLAY INVISIBLE (-2800 1250);
FORCEPROP 1 LAST HDL_TAP TRUE
J 2
(-3125 1175);
DISPLAY 1.595745 (-3125 1175);
PAINT GREEN (-3125 1175);
DISPLAY INVISIBLE (-3125 1175);
FORCEPROP 1 LAST PATH I99
J 2
(-2798 1300);
DISPLAY 0.872340 (-2798 1300);
PAINT GREEN (-2798 1300);
DISPLAY INVISIBLE (-2798 1300);
FORCEADD DESIGN_NOTE..1
(-6375 375);
FORCEPROP 0 LAST L1 CPU SYMBOLS 1-30 ARE PRELIMINARY AND SUBJECT TO CHANGE
J 0
(-6575 250);
DISPLAY 1.021277 (-6575 250);
PAINT ORANGE (-6575 250);
FORCEPROP 2 LAST CDS_LIB mstr_symbols
J 0
(-6375 375);
PAINT ORANGE (-6375 375);
DISPLAY INVISIBLE (-6375 375);
FORCEPROP 1 LAST COMMENT_BODY TRUE
J 0
(-6350 475);
DISPLAY 0.978723 (-6350 475);
PAINT ORANGE (-6350 475);
DISPLAY INVISIBLE (-6350 475);
FORCEADD PRELIM..10
(-4165 2540);
PAINT GRAY (-4165 2540);
FORCEPROP 2 LAST CDS_LIB mstr_misc
J 0
(-4165 2540);
PAINT ORANGE (-4165 2540);
DISPLAY INVISIBLE (-4165 2540);
FORCEPROP 1 LAST COMMENT_BODY TRUE
J 0
(-4165 2540);
PAINT ORANGE (-4165 2540);
DISPLAY INVISIBLE (-4165 2540);
FORCEADD INTEL_CORP_BPAGE..1
(0 0);
FORCEPROP 1 LAST CDS_CON_LAST_MODIFIED Tue Dec 01 11:51:16 2015
J 0
(-1425 325);
DISPLAY 1.340426 (-1425 325);
PAINT GREEN (-1425 325);
DISPLAY INVISIBLE (-1425 325);
FORCEPROP 1 LAST CUSTOM_TXT_CDS <CURRENT_DESIGN_SHEET> OF <TOTAL_DESIGN_SHEETS>
J 0
(-500 25);
PAINT GREEN (-500 25);
FORCEPROP 1 LAST CUSTOM_TXT_CDS <CON_LAST_MODIFIED>
J 0
(-1925 350);
PAINT GREEN (-1925 350);
FORCEPROP 2 LAST CUSTOM_TXT_CDS <XR_PAGE_TITLE>
J 0
(-7890 5250);
DISPLAY 0.638298 (-7890 5250);
PAINT PINK (-7890 5250);
DISPLAY INVISIBLE (-7890 5250);
FORCEPROP 1 LAST SCH_ADDRESS3 Santa Clara, CA 95052-8119
J 0
(-3975 25);
DISPLAY 0.617021 (-3975 25);
PAINT GREEN (-3975 25);
FORCEPROP 1 LAST SCH_ADDRESS2 P.O. BOX 58119
J 0
(-3975 75);
DISPLAY 0.617021 (-3975 75);
PAINT GREEN (-3975 75);
FORCEPROP 1 LAST SCH_ADDRESS1 2200 Mission College Blvd.
J 0
(-3975 125);
DISPLAY 0.617021 (-3975 125);
PAINT GREEN (-3975 125);
FORCEPROP 1 LAST SCH_TITLE SKYLAKE - SKT0 - 4 OF 21
J 0
(-7950 50);
DISPLAY 1.212766 (-7950 50);
PAINT GREEN (-7950 50);
FORCEPROP 1 LAST SCH_NUMBER H4694802
J 0
(-1300 150);
DISPLAY 1.212766 (-1300 150);
PAINT YELLOW (-1300 150);
FORCEPROP 1 LAST SCH_DEPT BESD
J 1
(-4450 100);
DISPLAY 1.212766 (-4450 100);
PAINT YELLOW (-4450 100);
FORCEPROP 1 LAST SCH_REV 2.420
J 0
(-250 150);
DISPLAY 0.978723 (-250 150);
PAINT YELLOW (-250 150);
FORCEPROP 2 LAST PAGE_BORDER TRUE
J 0
(-7890 5250);
DISPLAY 0.851064 (-7890 5250);
PAINT PINK (-7890 5250);
DISPLAY INVISIBLE (-7890 5250);
FORCEPROP 2 LAST CDS_LIB mstr_symbols
J 0
(0 0);
PAINT ORANGE (0 0);
DISPLAY INVISIBLE (0 0);
FORCEPROP 1 LAST COMMENT_BODY TRUE
J 0
(12 12);
DISPLAY 0.638298 (12 12);
PAINT GREEN (12 12);
DISPLAY INVISIBLE (12 12);
FORCEPROP 2 LAST CDS_XR_PAGE_TITLE CR-24 : @BASEBOARD_FAB2_LIB.BASEBOARD_FAB2(SCH_1):PAGE24
J 0
(-7890 5250);
DISPLAY 0.638298 (-7890 5250);
PAINT PINK (-7890 5250);
DISPLAY INVISIBLE (-7890 5250);
WIRE 17 -1 (-5575 1725)(-5575 1775);
WIRE 17 -1 (-5575 1675)(-5575 1725);
WIRE 17 -1 (-5575 1775)(-5575 1825);
WIRE 17 -1 (-5575 1825)(-5575 1875);
WIRE 17 -1 (-5575 1625)(-5575 1675);
WIRE 17 -1 (-5575 1575)(-5575 1625);
WIRE 17 -1 (-5575 1875)(-5575 1925);
WIRE 17 -1 (-5575 1925)(-5575 1975);
WIRE 17 -1 (-5575 1525)(-5575 1575);
WIRE 17 -1 (-5575 1975)(-5575 2025);
WIRE 17 -1 (-5575 2025)(-5575 2075);
WIRE 17 -1 (-5575 2075)(-5575 2125);
WIRE 17 -1 (-5575 2125)(-5575 2175);
WIRE 17 -1 (-5575 2175)(-5575 2225);
WIRE 17 -1 (-5575 2225)(-5575 2275);
WIRE 17 -1 (-5575 2275)(-5575 2325);
WIRE 17 -1 (-5575 2325)(-5575 2375);
WIRE 17 -1 (-5575 2375)(-5575 2425);
WIRE 17 -1 (-5575 2425)(-5575 2475);
WIRE 17 -1 (-5575 2475)(-5575 2525);
WIRE 17 -1 (-5575 2525)(-5575 2575);
WIRE 17 -1 (-5575 2575)(-5575 2625);
WIRE 17 -1 (-5575 2625)(-5575 2675);
WIRE 17 -1 (-5575 2675)(-5575 2725);
WIRE 17 -1 (-5575 2725)(-5575 2775);
WIRE 17 -1 (-5575 2775)(-5575 2825);
WIRE 17 -1 (-5575 2825)(-5575 2875);
WIRE 17 -1 (-5575 2875)(-5575 2925);
WIRE 17 -1 (-5575 2925)(-5575 2975);
WIRE 17 -1 (-5575 2975)(-5575 3025);
WIRE 17 -1 (-5575 3025)(-5575 3075);
WIRE 17 -1 (-5575 3075)(-5575 3125);
WIRE 17 -1 (-5575 3125)(-5575 3175);
WIRE 17 -1 (-5575 3175)(-5575 3225);
WIRE 17 -1 (-5575 3225)(-5575 3275);
WIRE 17 -1 (-5575 3275)(-5575 3325);
WIRE 17 -1 (-5575 3325)(-5575 3375);
WIRE 17 -1 (-5575 3375)(-5575 3425);
WIRE 17 -1 (-5575 3425)(-5575 3475);
WIRE 17 -1 (-5575 3475)(-5575 3525);
WIRE 17 -1 (-5575 3525)(-5575 3575);
WIRE 17 -1 (-5575 3575)(-5575 3625);
WIRE 17 -1 (-5575 3625)(-5575 3675);
WIRE 17 -1 (-5575 3675)(-5575 3725);
WIRE 17 -1 (-5575 3725)(-5575 3775);
WIRE 17 -1 (-5575 3775)(-5575 3825);
WIRE 17 -1 (-5575 3825)(-5575 3875);
WIRE 17 -1 (-5575 3875)(-5575 3925);
WIRE 17 -1 (-5575 3925)(-5575 3975);
WIRE 17 -1 (-5575 3975)(-5575 4025);
WIRE 17 -1 (-5575 4025)(-5575 4075);
WIRE 17 -1 (-5575 4075)(-5575 4125);
WIRE 17 -1 (-5575 4125)(-5575 4175);
WIRE 17 -1 (-5575 4175)(-5575 4225);
WIRE 17 -1 (-5575 4225)(-5575 4275);
WIRE 17 -1 (-5575 4275)(-5575 4325);
WIRE 17 -1 (-5575 4325)(-5575 4375);
WIRE 17 -1 (-5575 4375)(-5575 4425);
WIRE 17 -1 (-5575 4425)(-5575 4475);
WIRE 17 -1 (-5575 4475)(-5575 4525);
WIRE 17 -1 (-5575 4525)(-5575 4575);
WIRE 17 -1 (-5575 4575)(-5575 4625);
WIRE 17 -1 (-5575 4625)(-5575 4675);
WIRE 17 -1 (-5575 4675)(-5575 4775);
WIRE 17 -1 (-5575 4775)(-6325 4775);
FORCEPROP 2 LAST SIG_NAME M_B_DQ<63:0>
J 0
(-6275 4785);
DISPLAY 0.617021 (-6275 4785);
PAINT ORANGE (-6275 4785);
WIRE 17 -1 (-5575 775)(-5575 800);
WIRE 17 -1 (-5575 725)(-5575 775);
WIRE 17 -1 (-5575 800)(-6325 800);
FORCEPROP 2 LAST SIG_NAME M_B_CLK_DN<3:0>
J 0
(-6275 810);
DISPLAY 0.617021 (-6275 810);
PAINT ORANGE (-6275 810);
WIRE 17 -1 (-5575 675)(-5575 725);
WIRE 17 -1 (-5575 625)(-5575 675);
WIRE 17 -1 (-5575 975)(-5575 1000);
WIRE 17 -1 (-5575 925)(-5575 975);
WIRE 17 -1 (-5575 1000)(-6325 1000);
FORCEPROP 2 LAST SIG_NAME M_B_CLK_DP<3:0>
J 0
(-6275 1010);
DISPLAY 0.617021 (-6275 1010);
PAINT ORANGE (-6275 1010);
WIRE 17 -1 (-5575 875)(-5575 925);
WIRE 17 -1 (-5575 825)(-5575 875);
WIRE 17 -1 (-5575 1425)(-5575 1450);
WIRE 17 -1 (-5575 1375)(-5575 1425);
WIRE 17 -1 (-5575 1450)(-6325 1450);
FORCEPROP 2 LAST SIG_NAME M_B_ECC<7:0>
J 0
(-6275 1460);
DISPLAY 0.617021 (-6275 1460);
PAINT ORANGE (-6275 1460);
WIRE 17 -1 (-5575 1325)(-5575 1375);
WIRE 17 -1 (-5575 1275)(-5575 1325);
WIRE 17 -1 (-5575 1225)(-5575 1275);
WIRE 17 -1 (-5575 1175)(-5575 1225);
WIRE 17 -1 (-5575 1125)(-5575 1175);
WIRE 17 -1 (-5575 1075)(-5575 1125);
WIRE 17 -1 (-2750 775)(-2750 800);
WIRE 17 -1 (-2750 725)(-2750 775);
WIRE 17 -1 (-2000 800)(-2750 800);
FORCEPROP 2 LAST SIG_NAME M_B_BA<1:0>
J 0
(-2650 810);
DISPLAY 0.617021 (-2650 810);
PAINT ORANGE (-2650 810);
WIRE 17 -1 (-2750 875)(-2750 900);
WIRE 17 -1 (-2750 825)(-2750 875);
WIRE 17 -1 (-2000 900)(-2750 900);
FORCEPROP 2 LAST SIG_NAME M_B_BG<1:0>
J 0
(-2650 910);
DISPLAY 0.617021 (-2650 910);
PAINT ORANGE (-2650 910);
WIRE 17 -1 (-2750 1825)(-2750 1850);
WIRE 17 -1 (-2750 1775)(-2750 1825);
WIRE 17 -1 (-2000 1850)(-2750 1850);
FORCEPROP 2 LAST SIG_NAME M_B_CKE<3:0>
J 0
(-2650 1860);
DISPLAY 0.617021 (-2650 1860);
PAINT ORANGE (-2650 1860);
WIRE 17 -1 (-2750 1725)(-2750 1775);
WIRE 17 -1 (-2750 1675)(-2750 1725);
WIRE 17 -1 (-2750 1325)(-2750 1350);
WIRE 17 -1 (-2750 1275)(-2750 1325);
WIRE 17 -1 (-2000 1350)(-2750 1350);
FORCEPROP 2 LAST SIG_NAME M_B_CS_N<7:0>
J 0
(-2650 1360);
DISPLAY 0.617021 (-2650 1360);
PAINT ORANGE (-2650 1360);
WIRE 17 -1 (-2750 1225)(-2750 1275);
WIRE 17 -1 (-2750 1175)(-2750 1225);
WIRE 17 -1 (-2750 1125)(-2750 1175);
WIRE 17 -1 (-2750 1075)(-2750 1125);
WIRE 17 -1 (-2750 1025)(-2750 1075);
WIRE 17 -1 (-2750 975)(-2750 1025);
WIRE 17 -1 (-2750 1975)(-2750 2025);
WIRE 17 -1 (-2750 1925)(-2750 1975);
WIRE 17 -1 (-2750 2025)(-2750 2075);
WIRE 17 -1 (-2750 2075)(-2750 2125);
WIRE 17 -1 (-2750 2125)(-2750 2175);
WIRE 17 -1 (-2750 2175)(-2750 2225);
WIRE 17 -1 (-2750 2225)(-2750 2275);
WIRE 17 -1 (-2750 2275)(-2750 2325);
WIRE 17 -1 (-2750 2325)(-2750 2375);
WIRE 17 -1 (-2750 2375)(-2750 2425);
WIRE 17 -1 (-2750 2425)(-2750 2475);
WIRE 17 -1 (-2750 2475)(-2750 2525);
WIRE 17 -1 (-2750 2525)(-2750 2575);
WIRE 17 -1 (-2750 2575)(-2750 2625);
WIRE 17 -1 (-2750 2625)(-2750 2675);
WIRE 17 -1 (-2750 2675)(-2750 2725);
WIRE 17 -1 (-2750 2725)(-2750 2775);
WIRE 17 -1 (-2750 2775)(-2750 2800);
WIRE 17 -1 (-2000 2800)(-2750 2800);
FORCEPROP 2 LAST SIG_NAME M_B_MA<17:0>
J 0
(-2650 2810);
DISPLAY 0.617021 (-2650 2810);
PAINT ORANGE (-2650 2810);
WIRE 17 -1 (-2750 1575)(-2750 1600);
WIRE 17 -1 (-2750 1525)(-2750 1575);
WIRE 17 -1 (-2000 1600)(-2750 1600);
FORCEPROP 2 LAST SIG_NAME M_B_ODT<3:0>
J 0
(-2650 1610);
DISPLAY 0.617021 (-2650 1610);
PAINT ORANGE (-2650 1610);
WIRE 17 -1 (-2750 1475)(-2750 1525);
WIRE 17 -1 (-2750 1425)(-2750 1475);
WIRE 17 -1 (-2750 3725)(-2750 3750);
WIRE 17 -1 (-2750 3675)(-2750 3725);
WIRE 17 -1 (-2000 3750)(-2750 3750);
FORCEPROP 2 LAST SIG_NAME M_B_DQS_DN<17:0>
J 0
(-2650 3760);
DISPLAY 0.617021 (-2650 3760);
PAINT ORANGE (-2650 3760);
WIRE 17 -1 (-2750 3625)(-2750 3675);
WIRE 17 -1 (-2750 3575)(-2750 3625);
WIRE 17 -1 (-2750 3525)(-2750 3575);
WIRE 17 -1 (-2750 3475)(-2750 3525);
WIRE 17 -1 (-2750 3425)(-2750 3475);
WIRE 17 -1 (-2750 3375)(-2750 3425);
WIRE 17 -1 (-2750 3325)(-2750 3375);
WIRE 17 -1 (-2750 3275)(-2750 3325);
WIRE 17 -1 (-2750 3225)(-2750 3275);
WIRE 17 -1 (-2750 3175)(-2750 3225);
WIRE 17 -1 (-2750 3125)(-2750 3175);
WIRE 17 -1 (-2750 3075)(-2750 3125);
WIRE 17 -1 (-2750 3025)(-2750 3075);
WIRE 17 -1 (-2750 2975)(-2750 3025);
WIRE 17 -1 (-2750 2925)(-2750 2975);
WIRE 17 -1 (-2750 2875)(-2750 2925);
WIRE 17 -1 (-2750 4025)(-2750 4075);
WIRE 17 -1 (-2750 3975)(-2750 4025);
WIRE 17 -1 (-2750 4075)(-2750 4125);
WIRE 17 -1 (-2750 4125)(-2750 4175);
WIRE 17 -1 (-2750 3925)(-2750 3975);
WIRE 17 -1 (-2750 3875)(-2750 3925);
WIRE 17 -1 (-2750 4175)(-2750 4225);
WIRE 17 -1 (-2750 4225)(-2750 4275);
WIRE 17 -1 (-2750 3825)(-2750 3875);
WIRE 17 -1 (-2750 4275)(-2750 4325);
WIRE 17 -1 (-2750 4325)(-2750 4375);
WIRE 17 -1 (-2750 4375)(-2750 4425);
WIRE 17 -1 (-2750 4425)(-2750 4475);
WIRE 17 -1 (-2750 4475)(-2750 4525);
WIRE 17 -1 (-2750 4525)(-2750 4575);
WIRE 17 -1 (-2750 4575)(-2750 4625);
WIRE 17 -1 (-2750 4625)(-2750 4675);
WIRE 17 -1 (-2750 4675)(-2750 4725);
WIRE 17 -1 (-2000 4725)(-2750 4725);
FORCEPROP 2 LAST SIG_NAME M_B_DQS_DP<17:0>
J 0
(-2650 4735);
DISPLAY 0.617021 (-2650 4735);
PAINT ORANGE (-2650 4735);
WIRE 16 -1 (-3275 4100)(-2850 4100);
WIRE 16 -1 (-3275 4150)(-2850 4150);
WIRE 16 -1 (-3275 4200)(-2850 4200);
WIRE 16 -1 (-3275 4250)(-2850 4250);
WIRE 16 -1 (-3275 4300)(-2850 4300);
WIRE 16 -1 (-3275 4350)(-2850 4350);
WIRE 16 -1 (-3275 4400)(-2850 4400);
WIRE 16 -1 (-3275 4450)(-2850 4450);
WIRE 16 -1 (-3275 4500)(-2850 4500);
WIRE 16 -1 (-3275 4550)(-2850 4550);
WIRE 16 -1 (-3275 4600)(-2850 4600);
WIRE 16 -1 (-3275 4650)(-2850 4650);
WIRE 16 -1 (-3275 600)(-2000 600);
FORCEPROP 2 LAST SIG_NAME M_B_ACT_N
J 0
(-2700 610);
DISPLAY 0.617021 (-2700 610);
PAINT ORANGE (-2700 610);
WIRE 16 -1 (-3275 550)(-2000 550);
FORCEPROP 2 LAST SIG_NAME M_B_ALERT_N
J 0
(-2700 560);
DISPLAY 0.617021 (-2700 560);
PAINT ORANGE (-2700 560);
WIRE 16 -1 (-3275 500)(-2000 500);
FORCEPROP 2 LAST SIG_NAME M_B_PAR
J 0
(-2700 510);
DISPLAY 0.617021 (-2700 510);
PAINT ORANGE (-2700 510);
WIRE 16 -1 (-3275 2050)(-2850 2050);
WIRE 16 -1 (-3275 2100)(-2850 2100);
WIRE 16 -1 (-3275 2150)(-2850 2150);
WIRE 16 -1 (-3275 2200)(-2850 2200);
WIRE 16 -1 (-3275 2250)(-2850 2250);
WIRE 16 -1 (-3275 2300)(-2850 2300);
WIRE 16 -1 (-3275 2350)(-2850 2350);
WIRE 16 -1 (-3275 2400)(-2850 2400);
WIRE 16 -1 (-3275 2450)(-2850 2450);
WIRE 16 -1 (-3275 2500)(-2850 2500);
WIRE 16 -1 (-3275 2550)(-2850 2550);
WIRE 16 -1 (-3275 2600)(-2850 2600);
WIRE 16 -1 (-3275 2650)(-2850 2650);
WIRE 16 -1 (-3275 2700)(-2850 2700);
WIRE 16 -1 (-3275 2750)(-2850 2750);
WIRE 16 -1 (-3275 3800)(-2850 3800);
WIRE 16 -1 (-3275 3850)(-2850 3850);
WIRE 16 -1 (-3275 3900)(-2850 3900);
WIRE 16 -1 (-3275 3950)(-2850 3950);
WIRE 16 -1 (-3275 4000)(-2850 4000);
WIRE 16 -1 (-3275 4050)(-2850 4050);
WIRE 16 -1 (-3275 2850)(-2850 2850);
WIRE 16 -1 (-3275 2900)(-2850 2900);
WIRE 16 -1 (-3275 2950)(-2850 2950);
WIRE 16 -1 (-3275 3000)(-2850 3000);
WIRE 16 -1 (-3275 3050)(-2850 3050);
WIRE 16 -1 (-3275 3100)(-2850 3100);
WIRE 16 -1 (-3275 3150)(-2850 3150);
WIRE 16 -1 (-3275 3200)(-2850 3200);
WIRE 16 -1 (-3275 3250)(-2850 3250);
WIRE 16 -1 (-3275 3300)(-2850 3300);
WIRE 16 -1 (-3275 3350)(-2850 3350);
WIRE 16 -1 (-3275 3400)(-2850 3400);
WIRE 16 -1 (-3275 3450)(-2850 3450);
WIRE 16 -1 (-3275 3500)(-2850 3500);
WIRE 16 -1 (-3275 3550)(-2850 3550);
WIRE 16 -1 (-3275 3600)(-2850 3600);
WIRE 16 -1 (-3275 3650)(-2850 3650);
WIRE 16 -1 (-3275 3700)(-2850 3700);
WIRE 16 -1 (-3275 1400)(-2850 1400);
WIRE 16 -1 (-3275 1450)(-2850 1450);
WIRE 16 -1 (-3275 1500)(-2850 1500);
WIRE 16 -1 (-3275 1550)(-2850 1550);
WIRE 16 -1 (-3275 1900)(-2850 1900);
WIRE 16 -1 (-3275 1950)(-2850 1950);
WIRE 16 -1 (-3275 2000)(-2850 2000);
WIRE 16 -1 (-3275 950)(-2850 950);
WIRE 16 -1 (-3275 1000)(-2850 1000);
WIRE 16 -1 (-3275 1050)(-2850 1050);
WIRE 16 -1 (-3275 1100)(-2850 1100);
WIRE 16 -1 (-3275 1150)(-2850 1150);
WIRE 16 -1 (-3275 1200)(-2850 1200);
WIRE 16 -1 (-3275 1250)(-2850 1250);
WIRE 16 -1 (-3275 1300)(-2850 1300);
WIRE 16 -1 (-3275 1650)(-2850 1650);
WIRE 16 -1 (-3275 1700)(-2850 1700);
WIRE 16 -1 (-3275 1750)(-2850 1750);
WIRE 16 -1 (-3275 1800)(-2850 1800);
WIRE 16 -1 (-3275 800)(-2850 800);
WIRE 16 -1 (-3275 850)(-2850 850);
WIRE 16 -1 (-3275 700)(-2850 700);
WIRE 16 -1 (-3275 750)(-2850 750);
WIRE 16 -1 (-5475 4100)(-4975 4100);
WIRE 16 -1 (-4975 4150)(-5475 4150);
WIRE 16 -1 (-4975 4200)(-5475 4200);
WIRE 16 -1 (-4975 4250)(-5475 4250);
WIRE 16 -1 (-4975 4300)(-5475 4300);
WIRE 16 -1 (-4975 4350)(-5475 4350);
WIRE 16 -1 (-4975 4400)(-5475 4400);
WIRE 16 -1 (-4975 4450)(-5475 4450);
WIRE 16 -1 (-4975 4500)(-5475 4500);
WIRE 16 -1 (-4975 4550)(-5475 4550);
WIRE 16 -1 (-4975 4600)(-5475 4600);
WIRE 16 -1 (-4975 4650)(-5475 4650);
WIRE 16 -1 (-5475 2050)(-4975 2050);
WIRE 16 -1 (-5475 2100)(-4975 2100);
WIRE 16 -1 (-5475 2150)(-4975 2150);
WIRE 16 -1 (-5475 2200)(-4975 2200);
WIRE 16 -1 (-5475 2250)(-4975 2250);
WIRE 16 -1 (-5475 2300)(-4975 2300);
WIRE 16 -1 (-5475 2350)(-4975 2350);
WIRE 16 -1 (-5475 2400)(-4975 2400);
WIRE 16 -1 (-5475 2450)(-4975 2450);
WIRE 16 -1 (-5475 2500)(-4975 2500);
WIRE 16 -1 (-5475 2550)(-4975 2550);
WIRE 16 -1 (-5475 2600)(-4975 2600);
WIRE 16 -1 (-5475 2650)(-4975 2650);
WIRE 16 -1 (-5475 2700)(-4975 2700);
WIRE 16 -1 (-5475 2750)(-4975 2750);
WIRE 16 -1 (-5475 2800)(-4975 2800);
WIRE 16 -1 (-5475 2850)(-4975 2850);
WIRE 16 -1 (-5475 2900)(-4975 2900);
WIRE 16 -1 (-5475 2950)(-4975 2950);
WIRE 16 -1 (-5475 3000)(-4975 3000);
WIRE 16 -1 (-5475 3050)(-4975 3050);
WIRE 16 -1 (-5475 3100)(-4975 3100);
WIRE 16 -1 (-5475 3150)(-4975 3150);
WIRE 16 -1 (-5475 3200)(-4975 3200);
WIRE 16 -1 (-5475 3250)(-4975 3250);
WIRE 16 -1 (-5475 3300)(-4975 3300);
WIRE 16 -1 (-5475 3350)(-4975 3350);
WIRE 16 -1 (-5475 3400)(-4975 3400);
WIRE 16 -1 (-5475 3450)(-4975 3450);
WIRE 16 -1 (-5475 3500)(-4975 3500);
WIRE 16 -1 (-5475 3550)(-4975 3550);
WIRE 16 -1 (-5475 3600)(-4975 3600);
WIRE 16 -1 (-5475 3650)(-4975 3650);
WIRE 16 -1 (-4975 3700)(-5475 3700);
WIRE 16 -1 (-5475 3750)(-4975 3750);
WIRE 16 -1 (-5475 3800)(-4975 3800);
WIRE 16 -1 (-4975 3850)(-5475 3850);
WIRE 16 -1 (-5475 3900)(-4975 3900);
WIRE 16 -1 (-5475 3950)(-4975 3950);
WIRE 16 -1 (-4975 4000)(-5475 4000);
WIRE 16 -1 (-5475 4050)(-4975 4050);
WIRE 16 -1 (-5475 1050)(-4975 1050);
WIRE 16 -1 (-5475 1100)(-4975 1100);
WIRE 16 -1 (-5475 1150)(-4975 1150);
WIRE 16 -1 (-5475 1200)(-4975 1200);
WIRE 16 -1 (-4975 1250)(-5475 1250);
WIRE 16 -1 (-5475 1300)(-4975 1300);
WIRE 16 -1 (-5475 1350)(-4975 1350);
WIRE 16 -1 (-4975 1400)(-5475 1400);
WIRE 16 -1 (-5475 1500)(-4975 1500);
WIRE 16 -1 (-5475 1550)(-4975 1550);
WIRE 16 -1 (-5475 1600)(-4975 1600);
WIRE 16 -1 (-5475 1650)(-4975 1650);
WIRE 16 -1 (-5475 1700)(-4975 1700);
WIRE 16 -1 (-5475 1800)(-4975 1800);
WIRE 16 -1 (-5475 1850)(-4975 1850);
WIRE 16 -1 (-5475 1900)(-4975 1900);
WIRE 16 -1 (-5475 1950)(-4975 1950);
WIRE 16 -1 (-5475 2000)(-4975 2000);
WIRE 16 -1 (-4975 800)(-5475 800);
WIRE 16 -1 (-4975 850)(-5475 850);
WIRE 16 -1 (-4975 900)(-5475 900);
WIRE 16 -1 (-4975 950)(-5475 950);
WIRE 16 -1 (-4975 600)(-5475 600);
WIRE 16 -1 (-4975 650)(-5475 650);
WIRE 16 -1 (-4975 700)(-5475 700);
WIRE 16 -1 (-4975 750)(-5475 750);
WIRE 16 -1 (-4975 500)(-6325 500);
FORCEPROP 2 LAST SIG_NAME M_B_C<2>
J 0
(-6275 510);
DISPLAY 0.617021 (-6275 510);
PAINT ORANGE (-6275 510);
WIRE 16 -1 (-5475 1750)(-4975 1750);
FORCENOTE
ROOM=CPU0
(-7925 350) 0;
DISPLAY LEFT (-7925 350);
DISPLAY 1.382979 (-7925 350);
PAINT PURPLE (-7925 350);
FORCENOTE
BOM_COST=PROC_SOCKET
(-7925 225) 0;
DISPLAY LEFT (-7925 225);
DISPLAY 1.382979 (-7925 225);
PAINT PURPLE (-7925 225);
QUIT
